FILE_TYPE = MACRO_DRAWING;
SET COLOR_WIRE YELLOW;
SET COLOR_PROP MONO;
SET COLOR_DOT WHITE;
SET COLOR_ARC YELLOW;
SET COLOR_BODY GREEN;
SET COLOR_NOTE MONO;
SET PROP_DISPLAY VALUE;
SET PAGE_NUMBER P44;
FORCEADD GND..1
(-2650 750);
FORCEPROP 3 LASTPIN (-2650 800) SIG_NAME GND\g
J 0
(-2640 810);
DISPLAY 0.659574 (-2640 810);
PAINT MONO (-2640 810);
DISPLAY INVISIBLE (-2640 810);
FORCEPROP 1 LAST VOLTAGE 0
J 0
(-2650 750);
PAINT SKYBLUE (-2650 750);
DISPLAY INVISIBLE (-2650 750);
FORCEPROP 2 LAST BOM_COST MEM
J 0
(-2650 755);
PAINT ORANGE (-2650 755);
DISPLAY INVISIBLE (-2650 755);
FORCEPROP 2 LAST CDS_LIB mstr_symbols
J 0
(-2650 750);
PAINT ORANGE (-2650 750);
DISPLAY INVISIBLE (-2650 750);
FORCEPROP 1 LAST SIZE 1B
J 0
(-2575 700);
DISPLAY 1.787234 (-2575 700);
PAINT GREEN (-2575 700);
DISPLAY INVISIBLE (-2575 700);
FORCEPROP 1 LAST BODY_TYPE PLUMBING
J 0
(-2695 707);
DISPLAY 0.340426 (-2695 707);
PAINT GREEN (-2695 707);
DISPLAY INVISIBLE (-2695 707);
FORCEPROP 1 LAST PATH I1
J 0
(-2575 750);
DISPLAY 0.872340 (-2575 750);
PAINT AQUA (-2575 750);
DISPLAY INVISIBLE (-2575 750);
FORCEPROP 2 LAST ROOM DDR4_CH_A
J 0
(-2650 755);
PAINT ORANGE (-2650 755);
DISPLAY INVISIBLE (-2650 755);
FORCEPROP 1 LAST HDL_POWER GND
J 0
(-2650 900);
DISPLAY 1.404255 (-2650 900);
PAINT GREEN (-2650 900);
DISPLAY INVISIBLE (-2650 900);
FORCEADD OFFPAGE..6
(-2100 1350);
FORCEPROP 2 LAST $XR0 43 
J 0
(-2379 1350);
DISPLAY 0.638298 (-2379 1350);
PAINT MONO (-2379 1350);
FORCEPROP 2 LAST $XR1 45 
J 0
(-2469 1350);
DISPLAY 0.638298 (-2469 1350);
PAINT MONO (-2469 1350);
FORCEPROP 2 LAST $XR2 46 
J 0
(-2559 1350);
DISPLAY 0.638298 (-2559 1350);
PAINT MONO (-2559 1350);
FORCEPROP 2 LAST $XR3 47 
J 0
(-2649 1350);
DISPLAY 0.638298 (-2649 1350);
PAINT MONO (-2649 1350);
FORCEPROP 2 LAST $XR4 48 
J 0
(-2739 1350);
DISPLAY 0.638298 (-2739 1350);
PAINT MONO (-2739 1350);
FORCEPROP 2 LAST $XR5 99 
J 0
(-2829 1350);
DISPLAY 0.638298 (-2829 1350);
PAINT MONO (-2829 1350);
FORCEPROP 2 LASTPIN (-2050 1350) SIG_NAME SMB_DDR_ABC_VPP_SDA
J 0
(-2010 1360);
DISPLAY 0.617021 (-2010 1360);
PAINT ORANGE (-2010 1360);
FORCEPROP 2 LAST CDS_LIB mstr_standard
J 0
(-2100 1350);
DISPLAY 0.787234 (-2100 1350);
PAINT MONO (-2100 1350);
DISPLAY INVISIBLE (-2100 1350);
FORCEPROP 1 LAST OFFPAGE TRUE
J 0
(-1775 1225);
DISPLAY 0.936170 (-1775 1225);
PAINT GREEN (-1775 1225);
DISPLAY INVISIBLE (-1775 1225);
FORCEPROP 1 LAST COMMENT_BODY TRUE
J 0
(-2000 1275);
DISPLAY 0.936170 (-2000 1275);
PAINT GREEN (-2000 1275);
DISPLAY INVISIBLE (-2000 1275);
FORCEPROP 2 LAST PATH I10
J 0
(-2375 1400);
DISPLAY 1.021277 (-2375 1400);
PAINT ORANGE (-2375 1400);
DISPLAY INVISIBLE (-2375 1400);
FORCEADD TAP..6
R 2
(100 3150);
FORCEPROP 3 LASTPIN (50 3150) SIG_NAME M_A_DQ<39>
J 0
(60 3160);
DISPLAY 0.659574 (60 3160);
PAINT MONO (60 3160);
DISPLAY INVISIBLE (60 3160);
FORCEPROP 1 LASTPIN (50 3150) BN 39
J 2
(100 3160);
DISPLAY 0.617021 (100 3160);
PAINT PINK (100 3160);
FORCEPROP 2 LAST CDS_LIB mstr_standard
J 2
(100 3150);
DISPLAY 0.787234 (100 3150);
PAINT MONO (100 3150);
DISPLAY INVISIBLE (100 3150);
FORCEPROP 1 LAST BODY_TYPE PLUMBING
J 2
(100 3100);
DISPLAY 1.234043 (100 3100);
PAINT GREEN (100 3100);
DISPLAY INVISIBLE (100 3100);
FORCEPROP 1 LAST HDL_TAP TRUE
J 2
(-225 3025);
DISPLAY 1.234043 (-225 3025);
PAINT GREEN (-225 3025);
DISPLAY INVISIBLE (-225 3025);
FORCEPROP 1 LAST PATH I100
J 2
(102 3150);
DISPLAY 0.872340 (102 3150);
PAINT GREEN (102 3150);
DISPLAY INVISIBLE (102 3150);
FORCEADD TAP..6
R 2
(100 3200);
FORCEPROP 3 LASTPIN (50 3200) SIG_NAME M_A_DQ<40>
J 0
(60 3210);
DISPLAY 0.659574 (60 3210);
PAINT MONO (60 3210);
DISPLAY INVISIBLE (60 3210);
FORCEPROP 1 LASTPIN (50 3200) BN 40
J 2
(100 3210);
DISPLAY 0.617021 (100 3210);
PAINT PINK (100 3210);
FORCEPROP 2 LAST CDS_LIB mstr_standard
J 2
(100 3200);
DISPLAY 0.787234 (100 3200);
PAINT MONO (100 3200);
DISPLAY INVISIBLE (100 3200);
FORCEPROP 1 LAST BODY_TYPE PLUMBING
J 2
(100 3150);
DISPLAY 1.234043 (100 3150);
PAINT GREEN (100 3150);
DISPLAY INVISIBLE (100 3150);
FORCEPROP 1 LAST HDL_TAP TRUE
J 2
(-225 3075);
DISPLAY 1.234043 (-225 3075);
PAINT GREEN (-225 3075);
DISPLAY INVISIBLE (-225 3075);
FORCEPROP 1 LAST PATH I101
J 2
(102 3200);
DISPLAY 0.872340 (102 3200);
PAINT GREEN (102 3200);
DISPLAY INVISIBLE (102 3200);
FORCEADD TAP..6
R 2
(100 3250);
FORCEPROP 3 LASTPIN (50 3250) SIG_NAME M_A_DQ<41>
J 0
(60 3260);
DISPLAY 0.659574 (60 3260);
PAINT MONO (60 3260);
DISPLAY INVISIBLE (60 3260);
FORCEPROP 1 LASTPIN (50 3250) BN 41
J 2
(100 3260);
DISPLAY 0.617021 (100 3260);
PAINT PINK (100 3260);
FORCEPROP 2 LAST CDS_LIB mstr_standard
J 2
(100 3250);
DISPLAY 0.787234 (100 3250);
PAINT MONO (100 3250);
DISPLAY INVISIBLE (100 3250);
FORCEPROP 1 LAST BODY_TYPE PLUMBING
J 2
(100 3200);
DISPLAY 1.234043 (100 3200);
PAINT GREEN (100 3200);
DISPLAY INVISIBLE (100 3200);
FORCEPROP 1 LAST HDL_TAP TRUE
J 2
(-225 3125);
DISPLAY 1.234043 (-225 3125);
PAINT GREEN (-225 3125);
DISPLAY INVISIBLE (-225 3125);
FORCEPROP 1 LAST PATH I102
J 2
(102 3250);
DISPLAY 0.872340 (102 3250);
PAINT GREEN (102 3250);
DISPLAY INVISIBLE (102 3250);
FORCEADD TAP..6
R 2
(100 3300);
FORCEPROP 3 LASTPIN (50 3300) SIG_NAME M_A_DQ<42>
J 0
(60 3310);
DISPLAY 0.659574 (60 3310);
PAINT MONO (60 3310);
DISPLAY INVISIBLE (60 3310);
FORCEPROP 1 LASTPIN (50 3300) BN 42
J 2
(100 3310);
DISPLAY 0.617021 (100 3310);
PAINT PINK (100 3310);
FORCEPROP 2 LAST CDS_LIB mstr_standard
J 2
(100 3300);
DISPLAY 0.787234 (100 3300);
PAINT MONO (100 3300);
DISPLAY INVISIBLE (100 3300);
FORCEPROP 1 LAST BODY_TYPE PLUMBING
J 2
(100 3250);
DISPLAY 1.234043 (100 3250);
PAINT GREEN (100 3250);
DISPLAY INVISIBLE (100 3250);
FORCEPROP 1 LAST HDL_TAP TRUE
J 2
(-225 3175);
DISPLAY 1.234043 (-225 3175);
PAINT GREEN (-225 3175);
DISPLAY INVISIBLE (-225 3175);
FORCEPROP 1 LAST PATH I103
J 2
(102 3300);
DISPLAY 0.872340 (102 3300);
PAINT GREEN (102 3300);
DISPLAY INVISIBLE (102 3300);
FORCEADD TAP..6
R 2
(100 3400);
FORCEPROP 3 LASTPIN (50 3400) SIG_NAME M_A_DQ<44>
J 0
(60 3410);
DISPLAY 0.659574 (60 3410);
PAINT MONO (60 3410);
DISPLAY INVISIBLE (60 3410);
FORCEPROP 1 LASTPIN (50 3400) BN 44
J 2
(100 3410);
DISPLAY 0.617021 (100 3410);
PAINT PINK (100 3410);
FORCEPROP 2 LAST CDS_LIB mstr_standard
J 2
(100 3400);
DISPLAY 0.787234 (100 3400);
PAINT MONO (100 3400);
DISPLAY INVISIBLE (100 3400);
FORCEPROP 1 LAST BODY_TYPE PLUMBING
J 2
(100 3350);
DISPLAY 1.234043 (100 3350);
PAINT GREEN (100 3350);
DISPLAY INVISIBLE (100 3350);
FORCEPROP 1 LAST HDL_TAP TRUE
J 2
(-225 3275);
DISPLAY 1.234043 (-225 3275);
PAINT GREEN (-225 3275);
DISPLAY INVISIBLE (-225 3275);
FORCEPROP 1 LAST PATH I104
J 2
(102 3400);
DISPLAY 0.872340 (102 3400);
PAINT GREEN (102 3400);
DISPLAY INVISIBLE (102 3400);
FORCEADD TAP..6
R 2
(100 3350);
FORCEPROP 3 LASTPIN (50 3350) SIG_NAME M_A_DQ<43>
J 0
(60 3360);
DISPLAY 0.659574 (60 3360);
PAINT MONO (60 3360);
DISPLAY INVISIBLE (60 3360);
FORCEPROP 1 LASTPIN (50 3350) BN 43
J 2
(100 3360);
DISPLAY 0.617021 (100 3360);
PAINT PINK (100 3360);
FORCEPROP 2 LAST CDS_LIB mstr_standard
J 2
(100 3350);
DISPLAY 0.787234 (100 3350);
PAINT MONO (100 3350);
DISPLAY INVISIBLE (100 3350);
FORCEPROP 1 LAST BODY_TYPE PLUMBING
J 2
(100 3300);
DISPLAY 1.234043 (100 3300);
PAINT GREEN (100 3300);
DISPLAY INVISIBLE (100 3300);
FORCEPROP 1 LAST HDL_TAP TRUE
J 2
(-225 3225);
DISPLAY 1.234043 (-225 3225);
PAINT GREEN (-225 3225);
DISPLAY INVISIBLE (-225 3225);
FORCEPROP 1 LAST PATH I105
J 2
(102 3350);
DISPLAY 0.872340 (102 3350);
PAINT GREEN (102 3350);
DISPLAY INVISIBLE (102 3350);
FORCEADD TAP..6
R 2
(100 3450);
FORCEPROP 3 LASTPIN (50 3450) SIG_NAME M_A_DQ<45>
J 0
(60 3460);
DISPLAY 0.659574 (60 3460);
PAINT MONO (60 3460);
DISPLAY INVISIBLE (60 3460);
FORCEPROP 1 LASTPIN (50 3450) BN 45
J 2
(100 3460);
DISPLAY 0.617021 (100 3460);
PAINT PINK (100 3460);
FORCEPROP 2 LAST CDS_LIB mstr_standard
J 2
(100 3450);
DISPLAY 0.787234 (100 3450);
PAINT MONO (100 3450);
DISPLAY INVISIBLE (100 3450);
FORCEPROP 1 LAST BODY_TYPE PLUMBING
J 2
(100 3400);
DISPLAY 1.234043 (100 3400);
PAINT GREEN (100 3400);
DISPLAY INVISIBLE (100 3400);
FORCEPROP 1 LAST HDL_TAP TRUE
J 2
(-225 3325);
DISPLAY 1.234043 (-225 3325);
PAINT GREEN (-225 3325);
DISPLAY INVISIBLE (-225 3325);
FORCEPROP 1 LAST PATH I106
J 2
(102 3450);
DISPLAY 0.872340 (102 3450);
PAINT GREEN (102 3450);
DISPLAY INVISIBLE (102 3450);
FORCEADD TAP..6
R 2
(100 3500);
FORCEPROP 3 LASTPIN (50 3500) SIG_NAME M_A_DQ<46>
J 0
(60 3510);
DISPLAY 0.659574 (60 3510);
PAINT MONO (60 3510);
DISPLAY INVISIBLE (60 3510);
FORCEPROP 1 LASTPIN (50 3500) BN 46
J 2
(100 3510);
DISPLAY 0.617021 (100 3510);
PAINT PINK (100 3510);
FORCEPROP 2 LAST CDS_LIB mstr_standard
J 2
(100 3500);
DISPLAY 0.787234 (100 3500);
PAINT MONO (100 3500);
DISPLAY INVISIBLE (100 3500);
FORCEPROP 1 LAST BODY_TYPE PLUMBING
J 2
(100 3450);
DISPLAY 1.234043 (100 3450);
PAINT GREEN (100 3450);
DISPLAY INVISIBLE (100 3450);
FORCEPROP 1 LAST HDL_TAP TRUE
J 2
(-225 3375);
DISPLAY 1.234043 (-225 3375);
PAINT GREEN (-225 3375);
DISPLAY INVISIBLE (-225 3375);
FORCEPROP 1 LAST PATH I107
J 2
(102 3500);
DISPLAY 0.872340 (102 3500);
PAINT GREEN (102 3500);
DISPLAY INVISIBLE (102 3500);
FORCEADD TAP..6
R 2
(100 3650);
FORCEPROP 3 LASTPIN (50 3650) SIG_NAME M_A_DQ<49>
J 0
(60 3660);
DISPLAY 0.659574 (60 3660);
PAINT MONO (60 3660);
DISPLAY INVISIBLE (60 3660);
FORCEPROP 1 LASTPIN (50 3650) BN 49
J 2
(100 3660);
DISPLAY 0.617021 (100 3660);
PAINT PINK (100 3660);
FORCEPROP 2 LAST CDS_LIB mstr_standard
J 2
(100 3650);
DISPLAY 0.787234 (100 3650);
PAINT MONO (100 3650);
DISPLAY INVISIBLE (100 3650);
FORCEPROP 1 LAST BODY_TYPE PLUMBING
J 2
(100 3600);
DISPLAY 1.234043 (100 3600);
PAINT GREEN (100 3600);
DISPLAY INVISIBLE (100 3600);
FORCEPROP 1 LAST HDL_TAP TRUE
J 2
(-225 3525);
DISPLAY 1.234043 (-225 3525);
PAINT GREEN (-225 3525);
DISPLAY INVISIBLE (-225 3525);
FORCEPROP 1 LAST PATH I108
J 2
(102 3650);
DISPLAY 0.872340 (102 3650);
PAINT GREEN (102 3650);
DISPLAY INVISIBLE (102 3650);
FORCEADD TAP..6
R 2
(100 3600);
FORCEPROP 3 LASTPIN (50 3600) SIG_NAME M_A_DQ<48>
J 0
(60 3610);
DISPLAY 0.659574 (60 3610);
PAINT MONO (60 3610);
DISPLAY INVISIBLE (60 3610);
FORCEPROP 1 LASTPIN (50 3600) BN 48
J 2
(100 3610);
DISPLAY 0.617021 (100 3610);
PAINT PINK (100 3610);
FORCEPROP 2 LAST CDS_LIB mstr_standard
J 2
(100 3600);
DISPLAY 0.787234 (100 3600);
PAINT MONO (100 3600);
DISPLAY INVISIBLE (100 3600);
FORCEPROP 1 LAST BODY_TYPE PLUMBING
J 2
(100 3550);
DISPLAY 1.234043 (100 3550);
PAINT GREEN (100 3550);
DISPLAY INVISIBLE (100 3550);
FORCEPROP 1 LAST HDL_TAP TRUE
J 2
(-225 3475);
DISPLAY 1.234043 (-225 3475);
PAINT GREEN (-225 3475);
DISPLAY INVISIBLE (-225 3475);
FORCEPROP 1 LAST PATH I109
J 2
(102 3600);
DISPLAY 0.872340 (102 3600);
PAINT GREEN (102 3600);
DISPLAY INVISIBLE (102 3600);
FORCEADD OFFPAGE..1
(-2100 1300);
FORCEPROP 2 LAST $XR0 99 
J 0
(-2381 1300);
DISPLAY 0.638298 (-2381 1300);
PAINT MONO (-2381 1300);
FORCEPROP 2 LAST $XR1 43 
J 0
(-2471 1300);
DISPLAY 0.638298 (-2471 1300);
PAINT MONO (-2471 1300);
FORCEPROP 2 LAST $XR2 45 
J 0
(-2561 1300);
DISPLAY 0.638298 (-2561 1300);
PAINT MONO (-2561 1300);
FORCEPROP 2 LAST $XR3 46 
J 0
(-2651 1300);
DISPLAY 0.638298 (-2651 1300);
PAINT MONO (-2651 1300);
FORCEPROP 2 LAST $XR4 47 
J 0
(-2741 1300);
DISPLAY 0.638298 (-2741 1300);
PAINT MONO (-2741 1300);
FORCEPROP 2 LAST $XR5 48 
J 0
(-2831 1300);
DISPLAY 0.638298 (-2831 1300);
PAINT MONO (-2831 1300);
FORCEPROP 2 LAST CDS_LIB mstr_standard
J 0
(-2100 1300);
DISPLAY 0.787234 (-2100 1300);
PAINT MONO (-2100 1300);
DISPLAY INVISIBLE (-2100 1300);
FORCEPROP 1 LAST OFFPAGE TRUE
J 0
(-1775 1175);
DISPLAY 0.936170 (-1775 1175);
PAINT GREEN (-1775 1175);
DISPLAY INVISIBLE (-1775 1175);
FORCEPROP 1 LAST COMMENT_BODY TRUE
J 0
(-1975 1200);
DISPLAY 0.936170 (-1975 1200);
PAINT GREEN (-1975 1200);
DISPLAY INVISIBLE (-1975 1200);
FORCEPROP 2 LAST PATH I11
J 0
(-2375 1350);
DISPLAY 1.021277 (-2375 1350);
PAINT ORANGE (-2375 1350);
DISPLAY INVISIBLE (-2375 1350);
FORCEADD TAP..6
R 2
(100 3550);
FORCEPROP 3 LASTPIN (50 3550) SIG_NAME M_A_DQ<47>
J 0
(60 3560);
DISPLAY 0.659574 (60 3560);
PAINT MONO (60 3560);
DISPLAY INVISIBLE (60 3560);
FORCEPROP 1 LASTPIN (50 3550) BN 47
J 2
(100 3560);
DISPLAY 0.617021 (100 3560);
PAINT PINK (100 3560);
FORCEPROP 2 LAST CDS_LIB mstr_standard
J 2
(100 3550);
DISPLAY 0.787234 (100 3550);
PAINT MONO (100 3550);
DISPLAY INVISIBLE (100 3550);
FORCEPROP 1 LAST BODY_TYPE PLUMBING
J 2
(100 3500);
DISPLAY 1.234043 (100 3500);
PAINT GREEN (100 3500);
DISPLAY INVISIBLE (100 3500);
FORCEPROP 1 LAST HDL_TAP TRUE
J 2
(-225 3425);
DISPLAY 1.234043 (-225 3425);
PAINT GREEN (-225 3425);
DISPLAY INVISIBLE (-225 3425);
FORCEPROP 1 LAST PATH I110
J 2
(102 3550);
DISPLAY 0.872340 (102 3550);
PAINT GREEN (102 3550);
DISPLAY INVISIBLE (102 3550);
FORCEADD TAP..6
R 2
(100 3700);
FORCEPROP 3 LASTPIN (50 3700) SIG_NAME M_A_DQ<50>
J 0
(60 3710);
DISPLAY 0.659574 (60 3710);
PAINT MONO (60 3710);
DISPLAY INVISIBLE (60 3710);
FORCEPROP 1 LASTPIN (50 3700) BN 50
J 2
(100 3710);
DISPLAY 0.617021 (100 3710);
PAINT PINK (100 3710);
FORCEPROP 2 LAST CDS_LIB mstr_standard
J 2
(100 3700);
DISPLAY 0.787234 (100 3700);
PAINT MONO (100 3700);
DISPLAY INVISIBLE (100 3700);
FORCEPROP 1 LAST BODY_TYPE PLUMBING
J 2
(100 3650);
DISPLAY 1.234043 (100 3650);
PAINT GREEN (100 3650);
DISPLAY INVISIBLE (100 3650);
FORCEPROP 1 LAST HDL_TAP TRUE
J 2
(-225 3575);
DISPLAY 1.234043 (-225 3575);
PAINT GREEN (-225 3575);
DISPLAY INVISIBLE (-225 3575);
FORCEPROP 1 LAST PATH I111
J 2
(102 3700);
DISPLAY 0.872340 (102 3700);
PAINT GREEN (102 3700);
DISPLAY INVISIBLE (102 3700);
FORCEADD TAP..6
R 2
(100 3750);
FORCEPROP 3 LASTPIN (50 3750) SIG_NAME M_A_DQ<51>
J 0
(60 3760);
DISPLAY 0.659574 (60 3760);
PAINT MONO (60 3760);
DISPLAY INVISIBLE (60 3760);
FORCEPROP 1 LASTPIN (50 3750) BN 51
J 2
(100 3760);
DISPLAY 0.617021 (100 3760);
PAINT PINK (100 3760);
FORCEPROP 2 LAST CDS_LIB mstr_standard
J 2
(100 3750);
DISPLAY 0.787234 (100 3750);
PAINT MONO (100 3750);
DISPLAY INVISIBLE (100 3750);
FORCEPROP 1 LAST BODY_TYPE PLUMBING
J 2
(100 3700);
DISPLAY 1.234043 (100 3700);
PAINT GREEN (100 3700);
DISPLAY INVISIBLE (100 3700);
FORCEPROP 1 LAST HDL_TAP TRUE
J 2
(-225 3625);
DISPLAY 1.234043 (-225 3625);
PAINT GREEN (-225 3625);
DISPLAY INVISIBLE (-225 3625);
FORCEPROP 1 LAST PATH I112
J 2
(102 3750);
DISPLAY 0.872340 (102 3750);
PAINT GREEN (102 3750);
DISPLAY INVISIBLE (102 3750);
FORCEADD TAP..6
R 2
(100 3850);
FORCEPROP 3 LASTPIN (50 3850) SIG_NAME M_A_DQ<53>
J 0
(60 3860);
DISPLAY 0.659574 (60 3860);
PAINT MONO (60 3860);
DISPLAY INVISIBLE (60 3860);
FORCEPROP 1 LASTPIN (50 3850) BN 53
J 2
(100 3860);
DISPLAY 0.617021 (100 3860);
PAINT PINK (100 3860);
FORCEPROP 2 LAST CDS_LIB mstr_standard
J 2
(100 3850);
DISPLAY 0.787234 (100 3850);
PAINT MONO (100 3850);
DISPLAY INVISIBLE (100 3850);
FORCEPROP 1 LAST BODY_TYPE PLUMBING
J 2
(100 3800);
DISPLAY 1.234043 (100 3800);
PAINT GREEN (100 3800);
DISPLAY INVISIBLE (100 3800);
FORCEPROP 1 LAST HDL_TAP TRUE
J 2
(-225 3725);
DISPLAY 1.234043 (-225 3725);
PAINT GREEN (-225 3725);
DISPLAY INVISIBLE (-225 3725);
FORCEPROP 1 LAST PATH I113
J 2
(102 3850);
DISPLAY 0.872340 (102 3850);
PAINT GREEN (102 3850);
DISPLAY INVISIBLE (102 3850);
FORCEADD TAP..6
R 2
(100 3800);
FORCEPROP 3 LASTPIN (50 3800) SIG_NAME M_A_DQ<52>
J 0
(60 3810);
DISPLAY 0.659574 (60 3810);
PAINT MONO (60 3810);
DISPLAY INVISIBLE (60 3810);
FORCEPROP 1 LASTPIN (50 3800) BN 52
J 2
(100 3810);
DISPLAY 0.617021 (100 3810);
PAINT PINK (100 3810);
FORCEPROP 2 LAST CDS_LIB mstr_standard
J 2
(100 3800);
DISPLAY 0.787234 (100 3800);
PAINT MONO (100 3800);
DISPLAY INVISIBLE (100 3800);
FORCEPROP 1 LAST BODY_TYPE PLUMBING
J 2
(100 3750);
DISPLAY 1.234043 (100 3750);
PAINT GREEN (100 3750);
DISPLAY INVISIBLE (100 3750);
FORCEPROP 1 LAST HDL_TAP TRUE
J 2
(-225 3675);
DISPLAY 1.234043 (-225 3675);
PAINT GREEN (-225 3675);
DISPLAY INVISIBLE (-225 3675);
FORCEPROP 1 LAST PATH I114
J 2
(102 3800);
DISPLAY 0.872340 (102 3800);
PAINT GREEN (102 3800);
DISPLAY INVISIBLE (102 3800);
FORCEADD TAP..6
R 2
(100 3900);
FORCEPROP 3 LASTPIN (50 3900) SIG_NAME M_A_DQ<54>
J 0
(60 3910);
DISPLAY 0.659574 (60 3910);
PAINT MONO (60 3910);
DISPLAY INVISIBLE (60 3910);
FORCEPROP 1 LASTPIN (50 3900) BN 54
J 2
(100 3910);
DISPLAY 0.617021 (100 3910);
PAINT PINK (100 3910);
FORCEPROP 2 LAST CDS_LIB mstr_standard
J 2
(100 3900);
DISPLAY 0.787234 (100 3900);
PAINT MONO (100 3900);
DISPLAY INVISIBLE (100 3900);
FORCEPROP 1 LAST BODY_TYPE PLUMBING
J 2
(100 3850);
DISPLAY 1.234043 (100 3850);
PAINT GREEN (100 3850);
DISPLAY INVISIBLE (100 3850);
FORCEPROP 1 LAST HDL_TAP TRUE
J 2
(-225 3775);
DISPLAY 1.234043 (-225 3775);
PAINT GREEN (-225 3775);
DISPLAY INVISIBLE (-225 3775);
FORCEPROP 1 LAST PATH I115
J 2
(102 3900);
DISPLAY 0.872340 (102 3900);
PAINT GREEN (102 3900);
DISPLAY INVISIBLE (102 3900);
FORCEADD TAP..6
R 2
(100 3950);
FORCEPROP 3 LASTPIN (50 3950) SIG_NAME M_A_DQ<55>
J 0
(60 3960);
DISPLAY 0.659574 (60 3960);
PAINT MONO (60 3960);
DISPLAY INVISIBLE (60 3960);
FORCEPROP 1 LASTPIN (50 3950) BN 55
J 2
(100 3960);
DISPLAY 0.617021 (100 3960);
PAINT PINK (100 3960);
FORCEPROP 2 LAST CDS_LIB mstr_standard
J 2
(100 3950);
DISPLAY 0.787234 (100 3950);
PAINT MONO (100 3950);
DISPLAY INVISIBLE (100 3950);
FORCEPROP 1 LAST BODY_TYPE PLUMBING
J 2
(100 3900);
DISPLAY 1.234043 (100 3900);
PAINT GREEN (100 3900);
DISPLAY INVISIBLE (100 3900);
FORCEPROP 1 LAST HDL_TAP TRUE
J 2
(-225 3825);
DISPLAY 1.234043 (-225 3825);
PAINT GREEN (-225 3825);
DISPLAY INVISIBLE (-225 3825);
FORCEPROP 1 LAST PATH I116
J 2
(102 3950);
DISPLAY 0.872340 (102 3950);
PAINT GREEN (102 3950);
DISPLAY INVISIBLE (102 3950);
FORCEADD TAP..6
R 2
(100 4000);
FORCEPROP 3 LASTPIN (50 4000) SIG_NAME M_A_DQ<56>
J 0
(60 4010);
DISPLAY 0.659574 (60 4010);
PAINT MONO (60 4010);
DISPLAY INVISIBLE (60 4010);
FORCEPROP 1 LASTPIN (50 4000) BN 56
J 2
(100 4010);
DISPLAY 0.617021 (100 4010);
PAINT PINK (100 4010);
FORCEPROP 2 LAST CDS_LIB mstr_standard
J 2
(100 4000);
DISPLAY 0.787234 (100 4000);
PAINT MONO (100 4000);
DISPLAY INVISIBLE (100 4000);
FORCEPROP 1 LAST BODY_TYPE PLUMBING
J 2
(100 3950);
DISPLAY 1.234043 (100 3950);
PAINT GREEN (100 3950);
DISPLAY INVISIBLE (100 3950);
FORCEPROP 1 LAST HDL_TAP TRUE
J 2
(-225 3875);
DISPLAY 1.234043 (-225 3875);
PAINT GREEN (-225 3875);
DISPLAY INVISIBLE (-225 3875);
FORCEPROP 1 LAST PATH I117
J 2
(102 4000);
DISPLAY 0.872340 (102 4000);
PAINT GREEN (102 4000);
DISPLAY INVISIBLE (102 4000);
FORCEADD PVTT_ABC..1
(800 2350);
FORCEPROP 3 LASTPIN (800 2300) SIG_NAME PVTT_ABC\g
J 0
(810 2310);
DISPLAY 0.659574 (810 2310);
PAINT MONO (810 2310);
DISPLAY INVISIBLE (810 2310);
FORCEPROP 1 LAST VOLTAGE 0.6V
J 0
(755 2307);
DISPLAY 0.340426 (755 2307);
PAINT SKYBLUE (755 2307);
DISPLAY INVISIBLE (755 2307);
FORCEPROP 2 LAST BOM_COST MEM
J 0
(800 2355);
PAINT ORANGE (800 2355);
DISPLAY INVISIBLE (800 2355);
FORCEPROP 2 LAST CDS_LIB mstr_symbols
J 0
(800 2350);
PAINT ORANGE (800 2350);
DISPLAY INVISIBLE (800 2350);
FORCEPROP 1 LAST BODY_TYPE PLUMBING
J 0
(755 2307);
DISPLAY 0.340426 (755 2307);
PAINT GREEN (755 2307);
DISPLAY INVISIBLE (755 2307);
FORCEPROP 1 LAST PATH I118
J 0
(850 2375);
DISPLAY 0.872340 (850 2375);
PAINT AQUA (850 2375);
DISPLAY INVISIBLE (850 2375);
FORCEPROP 2 LAST ROOM DDR4_CH_A
J 0
(800 2355);
PAINT ORANGE (800 2355);
DISPLAY INVISIBLE (800 2355);
FORCEPROP 1 LAST HDL_POWER PVTT_ABC
J 1
(800 2400);
DISPLAY 0.872340 (800 2400);
PAINT GREEN (800 2400);
DISPLAY INVISIBLE (800 2400);
FORCEADD PVPP_ABC..1
(950 2650);
FORCEPROP 3 LASTPIN (950 2600) SIG_NAME PVPP_ABC\g
J 0
(960 2610);
DISPLAY 0.659574 (960 2610);
PAINT MONO (960 2610);
DISPLAY INVISIBLE (960 2610);
FORCEPROP 1 LAST VOLTAGE 2.5V
J 0
(905 2607);
DISPLAY 0.340426 (905 2607);
PAINT SKYBLUE (905 2607);
DISPLAY INVISIBLE (905 2607);
FORCEPROP 0 LAST BOM_COST MEM
J 0
(950 2750);
PAINT ORANGE (950 2750);
DISPLAY INVISIBLE (950 2750);
FORCEPROP 2 LAST CDS_LIB mstr_symbols
J 0
(950 2650);
PAINT ORANGE (950 2650);
DISPLAY INVISIBLE (950 2650);
FORCEPROP 1 LAST BODY_TYPE PLUMBING
J 0
(905 2607);
DISPLAY 0.340426 (905 2607);
PAINT GREEN (905 2607);
DISPLAY INVISIBLE (905 2607);
FORCEPROP 1 LAST PATH I119
J 0
(1000 2675);
DISPLAY 0.872340 (1000 2675);
PAINT AQUA (1000 2675);
DISPLAY INVISIBLE (1000 2675);
FORCEPROP 2 LAST ROOM DDR4_CH_A
J 0
(950 2750);
PAINT ORANGE (950 2750);
DISPLAY INVISIBLE (950 2750);
FORCEPROP 1 LAST HDL_POWER PVPP_ABC
J 1
(950 2700);
DISPLAY 0.872340 (950 2700);
PAINT GREEN (950 2700);
DISPLAY INVISIBLE (950 2700);
FORCEADD TAP..6
(-1450 1950);
FORCEPROP 3 LASTPIN (-1400 1950) SIG_NAME M_A_ECC<0>
J 0
(-1390 1960);
DISPLAY 0.659574 (-1390 1960);
PAINT MONO (-1390 1960);
DISPLAY INVISIBLE (-1390 1960);
FORCEPROP 1 LASTPIN (-1400 1950) BN 0
J 0
(-1450 1960);
DISPLAY 0.617021 (-1450 1960);
PAINT PINK (-1450 1960);
FORCEPROP 2 LAST CDS_LIB mstr_standard
J 0
(-1450 1950);
DISPLAY 0.787234 (-1450 1950);
PAINT MONO (-1450 1950);
DISPLAY INVISIBLE (-1450 1950);
FORCEPROP 1 LAST BODY_TYPE PLUMBING
J 0
(-1450 1900);
DISPLAY 1.234043 (-1450 1900);
PAINT GREEN (-1450 1900);
DISPLAY INVISIBLE (-1450 1900);
FORCEPROP 1 LAST HDL_TAP TRUE
J 0
(-1125 1825);
DISPLAY 1.234043 (-1125 1825);
PAINT GREEN (-1125 1825);
DISPLAY INVISIBLE (-1125 1825);
FORCEPROP 1 LAST PATH I12
J 0
(-1452 1950);
DISPLAY 0.872340 (-1452 1950);
PAINT GREEN (-1452 1950);
DISPLAY INVISIBLE (-1452 1950);
FORCEADD SCONN288_H44441003..2
(1650 4000);
FORCEPROP 1 LAST LOCATION J6T1
J 0
(1250 5100);
DISPLAY 0.617021 (1250 5100);
PAINT AQUA (1250 5100);
FORCEPROP 1 LAST PART_NUMBER H44441-003
J 0
(1250 2900);
DISPLAY 0.617021 (1250 2900);
PAINT BLUE (1250 2900);
FORCEPROP 1 LAST MATERIAL SCONN
J 0
(1250 5050);
DISPLAY 0.617021 (1250 5050);
PAINT SKYBLUE (1250 5050);
FORCEPROP 2 LASTPIN (2100 4850) $PN 51
J 0
(2110 4860);
DISPLAY 0.617021 (2110 4860);
PAINT ORANGE (2110 4860);
FORCEPROP 2 LASTPIN (2100 4800) $PN 52
J 0
(2110 4810);
DISPLAY 0.617021 (2110 4810);
PAINT ORANGE (2110 4810);
FORCEPROP 2 LASTPIN (2100 4750) $PN 132
J 0
(2110 4760);
DISPLAY 0.617021 (2110 4760);
PAINT ORANGE (2110 4760);
FORCEPROP 2 LASTPIN (2100 4700) $PN 133
J 0
(2110 4710);
DISPLAY 0.617021 (2110 4710);
PAINT ORANGE (2110 4710);
FORCEPROP 2 LASTPIN (2100 4650) $PN 121
J 0
(2110 4660);
DISPLAY 0.617021 (2110 4660);
PAINT ORANGE (2110 4660);
FORCEPROP 2 LASTPIN (2100 4600) $PN 122
J 0
(2110 4610);
DISPLAY 0.617021 (2110 4610);
PAINT ORANGE (2110 4610);
FORCEPROP 2 LASTPIN (2100 4550) $PN 110
J 0
(2110 4560);
DISPLAY 0.617021 (2110 4560);
PAINT ORANGE (2110 4560);
FORCEPROP 2 LASTPIN (2100 4500) $PN 111
J 0
(2110 4510);
DISPLAY 0.617021 (2110 4510);
PAINT ORANGE (2110 4510);
FORCEPROP 2 LASTPIN (2100 4450) $PN 99
J 0
(2110 4460);
DISPLAY 0.617021 (2110 4460);
PAINT ORANGE (2110 4460);
FORCEPROP 2 LASTPIN (2100 4400) $PN 100
J 0
(2110 4410);
DISPLAY 0.617021 (2110 4410);
PAINT ORANGE (2110 4410);
FORCEPROP 2 LASTPIN (2100 4350) $PN 40
J 0
(2110 4360);
DISPLAY 0.617021 (2110 4360);
PAINT ORANGE (2110 4360);
FORCEPROP 2 LASTPIN (2100 4300) $PN 41
J 0
(2110 4310);
DISPLAY 0.617021 (2110 4310);
PAINT ORANGE (2110 4310);
FORCEPROP 2 LASTPIN (2100 4250) $PN 29
J 0
(2110 4260);
DISPLAY 0.617021 (2110 4260);
PAINT ORANGE (2110 4260);
FORCEPROP 2 LASTPIN (2100 4200) $PN 30
J 0
(2110 4210);
DISPLAY 0.617021 (2110 4210);
PAINT ORANGE (2110 4210);
FORCEPROP 2 LASTPIN (2100 4150) $PN 18
J 0
(2110 4160);
DISPLAY 0.617021 (2110 4160);
PAINT ORANGE (2110 4160);
FORCEPROP 2 LASTPIN (2100 4100) $PN 19
J 0
(2110 4110);
DISPLAY 0.617021 (2110 4110);
PAINT ORANGE (2110 4110);
FORCEPROP 2 LASTPIN (2100 4050) $PN 7
J 0
(2110 4060);
DISPLAY 0.617021 (2110 4060);
PAINT ORANGE (2110 4060);
FORCEPROP 2 LASTPIN (2100 4000) $PN 8
J 0
(2110 4010);
DISPLAY 0.617021 (2110 4010);
PAINT ORANGE (2110 4010);
FORCEPROP 2 LASTPIN (2100 3950) $PN 197
J 0
(2110 3960);
DISPLAY 0.617021 (2110 3960);
PAINT ORANGE (2110 3960);
FORCEPROP 2 LASTPIN (2100 3900) $PN 196
J 0
(2110 3910);
DISPLAY 0.617021 (2110 3910);
PAINT ORANGE (2110 3910);
FORCEPROP 2 LASTPIN (2100 3850) $PN 278
J 0
(2110 3860);
DISPLAY 0.617021 (2110 3860);
PAINT ORANGE (2110 3860);
FORCEPROP 2 LASTPIN (2100 3800) $PN 277
J 0
(2110 3810);
DISPLAY 0.617021 (2110 3810);
PAINT ORANGE (2110 3810);
FORCEPROP 2 LASTPIN (2100 3750) $PN 267
J 0
(2110 3760);
DISPLAY 0.617021 (2110 3760);
PAINT ORANGE (2110 3760);
FORCEPROP 2 LASTPIN (2100 3700) $PN 266
J 0
(2110 3710);
DISPLAY 0.617021 (2110 3710);
PAINT ORANGE (2110 3710);
FORCEPROP 2 LASTPIN (2100 3650) $PN 256
J 0
(2110 3660);
DISPLAY 0.617021 (2110 3660);
PAINT ORANGE (2110 3660);
FORCEPROP 2 LASTPIN (2100 3600) $PN 255
J 0
(2110 3610);
DISPLAY 0.617021 (2110 3610);
PAINT ORANGE (2110 3610);
FORCEPROP 2 LASTPIN (2100 3550) $PN 245
J 0
(2110 3560);
DISPLAY 0.617021 (2110 3560);
PAINT ORANGE (2110 3560);
FORCEPROP 2 LASTPIN (2100 3500) $PN 244
J 0
(2110 3510);
DISPLAY 0.617021 (2110 3510);
PAINT ORANGE (2110 3510);
FORCEPROP 2 LASTPIN (2100 3450) $PN 186
J 0
(2110 3460);
DISPLAY 0.617021 (2110 3460);
PAINT ORANGE (2110 3460);
FORCEPROP 2 LASTPIN (2100 3400) $PN 185
J 0
(2110 3410);
DISPLAY 0.617021 (2110 3410);
PAINT ORANGE (2110 3410);
FORCEPROP 2 LASTPIN (2100 3350) $PN 175
J 0
(2110 3360);
DISPLAY 0.617021 (2110 3360);
PAINT ORANGE (2110 3360);
FORCEPROP 2 LASTPIN (2100 3300) $PN 174
J 0
(2110 3310);
DISPLAY 0.617021 (2110 3310);
PAINT ORANGE (2110 3310);
FORCEPROP 2 LASTPIN (2100 3250) $PN 164
J 0
(2110 3260);
DISPLAY 0.617021 (2110 3260);
PAINT ORANGE (2110 3260);
FORCEPROP 2 LASTPIN (2100 3200) $PN 163
J 0
(2110 3210);
DISPLAY 0.617021 (2110 3210);
PAINT ORANGE (2110 3210);
FORCEPROP 2 LASTPIN (2100 3150) $PN 153
J 0
(2110 3160);
DISPLAY 0.617021 (2110 3160);
PAINT ORANGE (2110 3160);
FORCEPROP 2 LASTPIN (2100 3100) $PN 152
J 0
(2110 3110);
DISPLAY 0.617021 (2110 3110);
PAINT ORANGE (2110 3110);
FORCEPROP 1 LAST PACK_TYPE PIP
J 0
(1250 5150);
PAINT SKYBLUE (1250 5150);
DISPLAY INVISIBLE (1250 5150);
FORCEPROP 2 LAST BOM_COST MEM
J 0
(1650 4000);
PAINT ORANGE (1650 4000);
DISPLAY INVISIBLE (1650 4000);
FORCEPROP 2 LAST CDS_LIB mstr_sconn
J 0
(1650 4000);
PAINT ORANGE (1650 4000);
DISPLAY INVISIBLE (1650 4000);
FORCEPROP 2 LAST SEC_TYPE PIP
J 0
(1250 5150);
DISPLAY 1.021277 (1250 5150);
PAINT ORANGE (1250 5150);
DISPLAY INVISIBLE (1250 5150);
FORCEPROP 2 LAST SEC 2
J 0
(1250 5150);
DISPLAY 0.680851 (1250 5150);
PAINT MONO (1250 5150);
DISPLAY INVISIBLE (1250 5150);
FORCEPROP 2 LAST CDS_LOCATION J6T1
J 0
(1250 5100);
DISPLAY 0.617021 (1250 5100);
PAINT AQUA (1250 5100);
DISPLAY INVISIBLE (1250 5100);
FORCEPROP 1 LAST PATH I120
J 0
(1650 5050);
PAINT GREEN (1650 5050);
DISPLAY INVISIBLE (1650 5050);
FORCEPROP 2 LAST ROOM DDR4_CH_A
J 0
(1650 4000);
PAINT ORANGE (1650 4000);
DISPLAY INVISIBLE (1650 4000);
FORCEADD OFFPAGE..1
(-2100 4400);
FORCEPROP 2 LAST $XR0 23 
J 0
(-2321 4400);
DISPLAY 0.638298 (-2321 4400);
PAINT MONO (-2321 4400);
FORCEPROP 2 LAST $XR1 43 
J 0
(-2411 4400);
DISPLAY 0.638298 (-2411 4400);
PAINT MONO (-2411 4400);
FORCEPROP 2 LAST CDS_LIB mstr_standard
J 0
(-2100 4400);
DISPLAY 0.787234 (-2100 4400);
PAINT MONO (-2100 4400);
DISPLAY INVISIBLE (-2100 4400);
FORCEPROP 1 LAST OFFPAGE TRUE
J 0
(-1775 4275);
DISPLAY 0.936170 (-1775 4275);
PAINT GREEN (-1775 4275);
DISPLAY INVISIBLE (-1775 4275);
FORCEPROP 1 LAST COMMENT_BODY TRUE
J 0
(-1975 4300);
DISPLAY 0.936170 (-1975 4300);
PAINT GREEN (-1975 4300);
DISPLAY INVISIBLE (-1975 4300);
FORCEPROP 2 LAST PATH I121
J 0
(-2300 4450);
DISPLAY 1.021277 (-2300 4450);
PAINT ORANGE (-2300 4450);
DISPLAY INVISIBLE (-2300 4450);
FORCEADD TAP..6
(-1450 4150);
FORCEPROP 3 LASTPIN (-1400 4150) SIG_NAME M_A_MA<13>
J 0
(-1390 4160);
DISPLAY 0.659574 (-1390 4160);
PAINT MONO (-1390 4160);
DISPLAY INVISIBLE (-1390 4160);
FORCEPROP 1 LASTPIN (-1400 4150) BN 13
J 0
(-1450 4160);
DISPLAY 0.617021 (-1450 4160);
PAINT PINK (-1450 4160);
FORCEPROP 2 LAST CDS_LIB mstr_standard
J 2
(-1450 4150);
DISPLAY 0.787234 (-1450 4150);
PAINT MONO (-1450 4150);
DISPLAY INVISIBLE (-1450 4150);
FORCEPROP 1 LAST BODY_TYPE PLUMBING
J 0
(-1450 4100);
DISPLAY 1.234043 (-1450 4100);
PAINT GREEN (-1450 4100);
DISPLAY INVISIBLE (-1450 4100);
FORCEPROP 1 LAST HDL_TAP TRUE
J 0
(-1125 4025);
DISPLAY 1.234043 (-1125 4025);
PAINT GREEN (-1125 4025);
DISPLAY INVISIBLE (-1125 4025);
FORCEPROP 1 LAST PATH I122
J 0
(-1452 4150);
DISPLAY 0.872340 (-1452 4150);
PAINT GREEN (-1452 4150);
DISPLAY INVISIBLE (-1452 4150);
FORCEADD TAP..6
(-1450 4050);
FORCEPROP 3 LASTPIN (-1400 4050) SIG_NAME M_A_MA<11>
J 0
(-1390 4060);
DISPLAY 0.659574 (-1390 4060);
PAINT MONO (-1390 4060);
DISPLAY INVISIBLE (-1390 4060);
FORCEPROP 1 LASTPIN (-1400 4050) BN 11
J 0
(-1450 4060);
DISPLAY 0.617021 (-1450 4060);
PAINT PINK (-1450 4060);
FORCEPROP 2 LAST CDS_LIB mstr_standard
J 2
(-1450 4050);
DISPLAY 0.787234 (-1450 4050);
PAINT MONO (-1450 4050);
DISPLAY INVISIBLE (-1450 4050);
FORCEPROP 1 LAST BODY_TYPE PLUMBING
J 0
(-1450 4000);
DISPLAY 1.234043 (-1450 4000);
PAINT GREEN (-1450 4000);
DISPLAY INVISIBLE (-1450 4000);
FORCEPROP 1 LAST HDL_TAP TRUE
J 0
(-1125 3925);
DISPLAY 1.234043 (-1125 3925);
PAINT GREEN (-1125 3925);
DISPLAY INVISIBLE (-1125 3925);
FORCEPROP 1 LAST PATH I123
J 0
(-1452 4050);
DISPLAY 0.872340 (-1452 4050);
PAINT GREEN (-1452 4050);
DISPLAY INVISIBLE (-1452 4050);
FORCEADD TAP..6
(-1450 4100);
FORCEPROP 3 LASTPIN (-1400 4100) SIG_NAME M_A_MA<12>
J 0
(-1390 4110);
DISPLAY 0.659574 (-1390 4110);
PAINT MONO (-1390 4110);
DISPLAY INVISIBLE (-1390 4110);
FORCEPROP 1 LASTPIN (-1400 4100) BN 12
J 0
(-1450 4110);
DISPLAY 0.617021 (-1450 4110);
PAINT PINK (-1450 4110);
FORCEPROP 2 LAST CDS_LIB mstr_standard
J 2
(-1450 4100);
DISPLAY 0.787234 (-1450 4100);
PAINT MONO (-1450 4100);
DISPLAY INVISIBLE (-1450 4100);
FORCEPROP 1 LAST BODY_TYPE PLUMBING
J 0
(-1450 4050);
DISPLAY 1.234043 (-1450 4050);
PAINT GREEN (-1450 4050);
DISPLAY INVISIBLE (-1450 4050);
FORCEPROP 1 LAST HDL_TAP TRUE
J 0
(-1125 3975);
DISPLAY 1.234043 (-1125 3975);
PAINT GREEN (-1125 3975);
DISPLAY INVISIBLE (-1125 3975);
FORCEPROP 1 LAST PATH I124
J 0
(-1452 4100);
DISPLAY 0.872340 (-1452 4100);
PAINT GREEN (-1452 4100);
DISPLAY INVISIBLE (-1452 4100);
FORCEADD TAP..6
(-1450 4200);
FORCEPROP 3 LASTPIN (-1400 4200) SIG_NAME M_A_MA<14>
J 0
(-1390 4210);
DISPLAY 0.659574 (-1390 4210);
PAINT MONO (-1390 4210);
DISPLAY INVISIBLE (-1390 4210);
FORCEPROP 1 LASTPIN (-1400 4200) BN 14
J 0
(-1450 4210);
DISPLAY 0.617021 (-1450 4210);
PAINT PINK (-1450 4210);
FORCEPROP 2 LAST CDS_LIB mstr_standard
J 2
(-1450 4200);
DISPLAY 0.787234 (-1450 4200);
PAINT MONO (-1450 4200);
DISPLAY INVISIBLE (-1450 4200);
FORCEPROP 1 LAST BODY_TYPE PLUMBING
J 0
(-1450 4150);
DISPLAY 1.234043 (-1450 4150);
PAINT GREEN (-1450 4150);
DISPLAY INVISIBLE (-1450 4150);
FORCEPROP 1 LAST HDL_TAP TRUE
J 0
(-1125 4075);
DISPLAY 1.234043 (-1125 4075);
PAINT GREEN (-1125 4075);
DISPLAY INVISIBLE (-1125 4075);
FORCEPROP 1 LAST PATH I125
J 0
(-1452 4200);
DISPLAY 0.872340 (-1452 4200);
PAINT GREEN (-1452 4200);
DISPLAY INVISIBLE (-1452 4200);
FORCEADD TAP..6
(-1450 4250);
FORCEPROP 3 LASTPIN (-1400 4250) SIG_NAME M_A_MA<15>
J 0
(-1390 4260);
DISPLAY 0.659574 (-1390 4260);
PAINT MONO (-1390 4260);
DISPLAY INVISIBLE (-1390 4260);
FORCEPROP 1 LASTPIN (-1400 4250) BN 15
J 0
(-1450 4260);
DISPLAY 0.617021 (-1450 4260);
PAINT PINK (-1450 4260);
FORCEPROP 2 LAST CDS_LIB mstr_standard
J 2
(-1450 4250);
DISPLAY 0.787234 (-1450 4250);
PAINT MONO (-1450 4250);
DISPLAY INVISIBLE (-1450 4250);
FORCEPROP 1 LAST BODY_TYPE PLUMBING
J 0
(-1450 4200);
DISPLAY 1.234043 (-1450 4200);
PAINT GREEN (-1450 4200);
DISPLAY INVISIBLE (-1450 4200);
FORCEPROP 1 LAST HDL_TAP TRUE
J 0
(-1125 4125);
DISPLAY 1.234043 (-1125 4125);
PAINT GREEN (-1125 4125);
DISPLAY INVISIBLE (-1125 4125);
FORCEPROP 1 LAST PATH I126
J 0
(-1452 4250);
DISPLAY 0.872340 (-1452 4250);
PAINT GREEN (-1452 4250);
DISPLAY INVISIBLE (-1452 4250);
FORCEADD TAP..6
(-1450 4300);
FORCEPROP 3 LASTPIN (-1400 4300) SIG_NAME M_A_MA<16>
J 0
(-1390 4310);
DISPLAY 0.659574 (-1390 4310);
PAINT MONO (-1390 4310);
DISPLAY INVISIBLE (-1390 4310);
FORCEPROP 1 LASTPIN (-1400 4300) BN 16
J 0
(-1450 4310);
DISPLAY 0.617021 (-1450 4310);
PAINT PINK (-1450 4310);
FORCEPROP 2 LAST CDS_LIB mstr_standard
J 2
(-1450 4300);
DISPLAY 0.787234 (-1450 4300);
PAINT MONO (-1450 4300);
DISPLAY INVISIBLE (-1450 4300);
FORCEPROP 1 LAST BODY_TYPE PLUMBING
J 0
(-1450 4250);
DISPLAY 1.234043 (-1450 4250);
PAINT GREEN (-1450 4250);
DISPLAY INVISIBLE (-1450 4250);
FORCEPROP 1 LAST HDL_TAP TRUE
J 0
(-1125 4175);
DISPLAY 1.234043 (-1125 4175);
PAINT GREEN (-1125 4175);
DISPLAY INVISIBLE (-1125 4175);
FORCEPROP 1 LAST PATH I127
J 0
(-1452 4300);
DISPLAY 0.872340 (-1452 4300);
PAINT GREEN (-1452 4300);
DISPLAY INVISIBLE (-1452 4300);
FORCEADD TAP..6
(-1450 4350);
FORCEPROP 3 LASTPIN (-1400 4350) SIG_NAME M_A_MA<17>
J 0
(-1390 4360);
DISPLAY 0.659574 (-1390 4360);
PAINT MONO (-1390 4360);
DISPLAY INVISIBLE (-1390 4360);
FORCEPROP 1 LASTPIN (-1400 4350) BN 17
J 0
(-1450 4360);
DISPLAY 0.617021 (-1450 4360);
PAINT PINK (-1450 4360);
FORCEPROP 2 LAST CDS_LIB mstr_standard
J 0
(-1450 4350);
DISPLAY 0.787234 (-1450 4350);
PAINT MONO (-1450 4350);
DISPLAY INVISIBLE (-1450 4350);
FORCEPROP 1 LAST BODY_TYPE PLUMBING
J 0
(-1450 4300);
DISPLAY 1.234043 (-1450 4300);
PAINT GREEN (-1450 4300);
DISPLAY INVISIBLE (-1450 4300);
FORCEPROP 1 LAST HDL_TAP TRUE
J 0
(-1125 4225);
DISPLAY 1.234043 (-1125 4225);
PAINT GREEN (-1125 4225);
DISPLAY INVISIBLE (-1125 4225);
FORCEPROP 1 LAST PATH I128
J 0
(-1452 4350);
DISPLAY 0.872340 (-1452 4350);
PAINT GREEN (-1452 4350);
DISPLAY INVISIBLE (-1452 4350);
FORCEADD TAP..6
R 2
(100 4050);
FORCEPROP 3 LASTPIN (50 4050) SIG_NAME M_A_DQ<57>
J 0
(60 4060);
DISPLAY 0.659574 (60 4060);
PAINT MONO (60 4060);
DISPLAY INVISIBLE (60 4060);
FORCEPROP 1 LASTPIN (50 4050) BN 57
J 2
(100 4060);
DISPLAY 0.617021 (100 4060);
PAINT PINK (100 4060);
FORCEPROP 2 LAST CDS_LIB mstr_standard
J 2
(100 4050);
DISPLAY 0.787234 (100 4050);
PAINT MONO (100 4050);
DISPLAY INVISIBLE (100 4050);
FORCEPROP 1 LAST BODY_TYPE PLUMBING
J 2
(100 4000);
DISPLAY 1.234043 (100 4000);
PAINT GREEN (100 4000);
DISPLAY INVISIBLE (100 4000);
FORCEPROP 1 LAST HDL_TAP TRUE
J 2
(-225 3925);
DISPLAY 1.234043 (-225 3925);
PAINT GREEN (-225 3925);
DISPLAY INVISIBLE (-225 3925);
FORCEPROP 1 LAST PATH I129
J 2
(102 4050);
DISPLAY 0.872340 (102 4050);
PAINT GREEN (102 4050);
DISPLAY INVISIBLE (102 4050);
FORCEADD SCONN288_H44441003..1
(-700 2700);
FORCEPROP 1 LAST LOCATION J6T1
J 0
(-1150 4600);
DISPLAY 0.617021 (-1150 4600);
PAINT AQUA (-1150 4600);
FORCEPROP 1 LAST PART_NUMBER H44441-003
J 0
(-1150 700);
DISPLAY 0.617021 (-1150 700);
PAINT BLUE (-1150 700);
FORCEPROP 1 LAST MATERIAL SCONN
J 0
(-1150 4550);
DISPLAY 0.617021 (-1150 4550);
PAINT SKYBLUE (-1150 4550);
FORCEPROP 2 LASTPIN (-1200 1200) $PN 146
J 2
(-1210 1210);
DISPLAY 0.617021 (-1210 1210);
PAINT ORANGE (-1210 1210);
FORCEPROP 2 LASTPIN (-1200 1550) $PN 284
J 2
(-1210 1560);
DISPLAY 0.617021 (-1210 1560);
PAINT ORANGE (-1210 1560);
FORCEPROP 2 LASTPIN (-1200 1350) $PN 285
J 2
(-1210 1360);
DISPLAY 0.617021 (-1210 1360);
PAINT ORANGE (-1210 1360);
FORCEPROP 2 LASTPIN (-1200 1300) $PN 141
J 2
(-1210 1310);
DISPLAY 0.617021 (-1210 1310);
PAINT ORANGE (-1210 1310);
FORCEPROP 2 LASTPIN (-1200 900) $PN 230
J 2
(-1210 910);
DISPLAY 0.617021 (-1210 910);
PAINT ORANGE (-1210 910);
FORCEPROP 2 LASTPIN (-1200 1500) $PN 238
J 2
(-1210 1510);
DISPLAY 0.617021 (-1210 1510);
PAINT ORANGE (-1210 1510);
FORCEPROP 2 LASTPIN (-1200 1450) $PN 140
J 2
(-1210 1460);
DISPLAY 0.617021 (-1210 1460);
PAINT ORANGE (-1210 1460);
FORCEPROP 2 LASTPIN (-1200 1400) $PN 139
J 2
(-1210 1410);
DISPLAY 0.617021 (-1210 1410);
PAINT ORANGE (-1210 1410);
FORCEPROP 2 LASTPIN (-1200 2850) $PN 237
J 2
(-1210 2860);
DISPLAY 0.617021 (-1210 2860);
PAINT ORANGE (-1210 2860);
FORCEPROP 2 LASTPIN (-1200 2800) $PN 93
J 2
(-1210 2810);
DISPLAY 0.617021 (-1210 2810);
PAINT ORANGE (-1210 2810);
FORCEPROP 2 LASTPIN (-1200 2750) $PN 89
J 2
(-1210 2760);
DISPLAY 0.617021 (-1210 2760);
PAINT ORANGE (-1210 2760);
FORCEPROP 2 LASTPIN (-1200 2700) $PN 84
J 2
(-1210 2710);
DISPLAY 0.617021 (-1210 2710);
PAINT ORANGE (-1210 2710);
FORCEPROP 2 LASTPIN (-1200 1100) $PN 144
J 2
(-1210 1110);
DISPLAY 0.617021 (-1210 1110);
PAINT ORANGE (-1210 1110);
FORCEPROP 2 LASTPIN (-1200 1050) $PN 227
J 2
(-1210 1060);
DISPLAY 0.617021 (-1210 1060);
PAINT ORANGE (-1210 1060);
FORCEPROP 2 LASTPIN (-1200 1000) $PN 205
J 2
(-1210 1010);
DISPLAY 0.617021 (-1210 1010);
PAINT ORANGE (-1210 1010);
FORCEPROP 2 LASTPIN (-1200 1800) $PN 58
J 2
(-1210 1810);
DISPLAY 0.617021 (-1210 1810);
PAINT ORANGE (-1210 1810);
FORCEPROP 2 LASTPIN (-1200 1850) $PN 222
J 2
(-1210 1860);
DISPLAY 0.617021 (-1210 1860);
PAINT ORANGE (-1210 1860);
FORCEPROP 2 LASTPIN (-1200 2450) $PN 91
J 2
(-1210 2460);
DISPLAY 0.617021 (-1210 2460);
PAINT ORANGE (-1210 2460);
FORCEPROP 2 LASTPIN (-1200 2400) $PN 87
J 2
(-1210 2410);
DISPLAY 0.617021 (-1210 2410);
PAINT ORANGE (-1210 2410);
FORCEPROP 2 LASTPIN (-1200 1750) $PN 78
J 2
(-1210 1760);
DISPLAY 0.617021 (-1210 1760);
PAINT ORANGE (-1210 1760);
FORCEPROP 2 LASTPIN (-200 4350) $PN 280
J 0
(-190 4360);
DISPLAY 0.617021 (-190 4360);
PAINT ORANGE (-190 4360);
FORCEPROP 2 LASTPIN (-200 4300) $PN 135
J 0
(-190 4310);
DISPLAY 0.617021 (-190 4310);
PAINT ORANGE (-190 4310);
FORCEPROP 2 LASTPIN (-200 4250) $PN 273
J 0
(-190 4260);
DISPLAY 0.617021 (-190 4260);
PAINT ORANGE (-190 4260);
FORCEPROP 2 LASTPIN (-200 4200) $PN 128
J 0
(-190 4210);
DISPLAY 0.617021 (-190 4210);
PAINT ORANGE (-190 4210);
FORCEPROP 2 LASTPIN (-200 4150) $PN 282
J 0
(-190 4160);
DISPLAY 0.617021 (-190 4160);
PAINT ORANGE (-190 4160);
FORCEPROP 2 LASTPIN (-200 4100) $PN 137
J 0
(-190 4110);
DISPLAY 0.617021 (-190 4110);
PAINT ORANGE (-190 4110);
FORCEPROP 2 LASTPIN (-200 4050) $PN 275
J 0
(-190 4060);
DISPLAY 0.617021 (-190 4060);
PAINT ORANGE (-190 4060);
FORCEPROP 2 LASTPIN (-200 4000) $PN 130
J 0
(-190 4010);
DISPLAY 0.617021 (-190 4010);
PAINT ORANGE (-190 4010);
FORCEPROP 2 LASTPIN (-200 3950) $PN 269
J 0
(-190 3960);
DISPLAY 0.617021 (-190 3960);
PAINT ORANGE (-190 3960);
FORCEPROP 2 LASTPIN (-200 3900) $PN 124
J 0
(-190 3910);
DISPLAY 0.617021 (-190 3910);
PAINT ORANGE (-190 3910);
FORCEPROP 2 LASTPIN (-200 3850) $PN 262
J 0
(-190 3860);
DISPLAY 0.617021 (-190 3860);
PAINT ORANGE (-190 3860);
FORCEPROP 2 LASTPIN (-200 3800) $PN 117
J 0
(-190 3810);
DISPLAY 0.617021 (-190 3810);
PAINT ORANGE (-190 3810);
FORCEPROP 2 LASTPIN (-200 3750) $PN 271
J 0
(-190 3760);
DISPLAY 0.617021 (-190 3760);
PAINT ORANGE (-190 3760);
FORCEPROP 2 LASTPIN (-200 3700) $PN 126
J 0
(-190 3710);
DISPLAY 0.617021 (-190 3710);
PAINT ORANGE (-190 3710);
FORCEPROP 2 LASTPIN (-200 3650) $PN 264
J 0
(-190 3660);
DISPLAY 0.617021 (-190 3660);
PAINT ORANGE (-190 3660);
FORCEPROP 2 LASTPIN (-200 3600) $PN 119
J 0
(-190 3610);
DISPLAY 0.617021 (-190 3610);
PAINT ORANGE (-190 3610);
FORCEPROP 2 LASTPIN (-200 3550) $PN 258
J 0
(-190 3560);
DISPLAY 0.617021 (-190 3560);
PAINT ORANGE (-190 3560);
FORCEPROP 2 LASTPIN (-200 3500) $PN 113
J 0
(-190 3510);
DISPLAY 0.617021 (-190 3510);
PAINT ORANGE (-190 3510);
FORCEPROP 2 LASTPIN (-200 3450) $PN 251
J 0
(-190 3460);
DISPLAY 0.617021 (-190 3460);
PAINT ORANGE (-190 3460);
FORCEPROP 2 LASTPIN (-200 3400) $PN 106
J 0
(-190 3410);
DISPLAY 0.617021 (-190 3410);
PAINT ORANGE (-190 3410);
FORCEPROP 2 LASTPIN (-200 3350) $PN 260
J 0
(-190 3360);
DISPLAY 0.617021 (-190 3360);
PAINT ORANGE (-190 3360);
FORCEPROP 2 LASTPIN (-200 3300) $PN 115
J 0
(-190 3310);
DISPLAY 0.617021 (-190 3310);
PAINT ORANGE (-190 3310);
FORCEPROP 2 LASTPIN (-200 3250) $PN 253
J 0
(-190 3260);
DISPLAY 0.617021 (-190 3260);
PAINT ORANGE (-190 3260);
FORCEPROP 2 LASTPIN (-200 3200) $PN 108
J 0
(-190 3210);
DISPLAY 0.617021 (-190 3210);
PAINT ORANGE (-190 3210);
FORCEPROP 2 LASTPIN (-200 3150) $PN 247
J 0
(-190 3160);
DISPLAY 0.617021 (-190 3160);
PAINT ORANGE (-190 3160);
FORCEPROP 2 LASTPIN (-200 3100) $PN 102
J 0
(-190 3110);
DISPLAY 0.617021 (-190 3110);
PAINT ORANGE (-190 3110);
FORCEPROP 2 LASTPIN (-200 3050) $PN 240
J 0
(-190 3060);
DISPLAY 0.617021 (-190 3060);
PAINT ORANGE (-190 3060);
FORCEPROP 2 LASTPIN (-200 3000) $PN 95
J 0
(-190 3010);
DISPLAY 0.617021 (-190 3010);
PAINT ORANGE (-190 3010);
FORCEPROP 2 LASTPIN (-200 2950) $PN 249
J 0
(-190 2960);
DISPLAY 0.617021 (-190 2960);
PAINT ORANGE (-190 2960);
FORCEPROP 2 LASTPIN (-200 2900) $PN 104
J 0
(-190 2910);
DISPLAY 0.617021 (-190 2910);
PAINT ORANGE (-190 2910);
FORCEPROP 2 LASTPIN (-200 2850) $PN 242
J 0
(-190 2860);
DISPLAY 0.617021 (-190 2860);
PAINT ORANGE (-190 2860);
FORCEPROP 2 LASTPIN (-200 2800) $PN 97
J 0
(-190 2810);
DISPLAY 0.617021 (-190 2810);
PAINT ORANGE (-190 2810);
FORCEPROP 2 LASTPIN (-200 2750) $PN 188
J 0
(-190 2760);
DISPLAY 0.617021 (-190 2760);
PAINT ORANGE (-190 2760);
FORCEPROP 2 LASTPIN (-200 2700) $PN 43
J 0
(-190 2710);
DISPLAY 0.617021 (-190 2710);
PAINT ORANGE (-190 2710);
FORCEPROP 2 LASTPIN (-200 2650) $PN 181
J 0
(-190 2660);
DISPLAY 0.617021 (-190 2660);
PAINT ORANGE (-190 2660);
FORCEPROP 2 LASTPIN (-200 2600) $PN 36
J 0
(-190 2610);
DISPLAY 0.617021 (-190 2610);
PAINT ORANGE (-190 2610);
FORCEPROP 2 LASTPIN (-200 2550) $PN 190
J 0
(-190 2560);
DISPLAY 0.617021 (-190 2560);
PAINT ORANGE (-190 2560);
FORCEPROP 2 LASTPIN (-200 2500) $PN 45
J 0
(-190 2510);
DISPLAY 0.617021 (-190 2510);
PAINT ORANGE (-190 2510);
FORCEPROP 2 LASTPIN (-200 2450) $PN 183
J 0
(-190 2460);
DISPLAY 0.617021 (-190 2460);
PAINT ORANGE (-190 2460);
FORCEPROP 2 LASTPIN (-200 2400) $PN 38
J 0
(-190 2410);
DISPLAY 0.617021 (-190 2410);
PAINT ORANGE (-190 2410);
FORCEPROP 2 LASTPIN (-200 2350) $PN 177
J 0
(-190 2360);
DISPLAY 0.617021 (-190 2360);
PAINT ORANGE (-190 2360);
FORCEPROP 2 LASTPIN (-200 2300) $PN 32
J 0
(-190 2310);
DISPLAY 0.617021 (-190 2310);
PAINT ORANGE (-190 2310);
FORCEPROP 2 LASTPIN (-200 2250) $PN 170
J 0
(-190 2260);
DISPLAY 0.617021 (-190 2260);
PAINT ORANGE (-190 2260);
FORCEPROP 2 LASTPIN (-200 2200) $PN 25
J 0
(-190 2210);
DISPLAY 0.617021 (-190 2210);
PAINT ORANGE (-190 2210);
FORCEPROP 2 LASTPIN (-200 2150) $PN 179
J 0
(-190 2160);
DISPLAY 0.617021 (-190 2160);
PAINT ORANGE (-190 2160);
FORCEPROP 2 LASTPIN (-200 2100) $PN 34
J 0
(-190 2110);
DISPLAY 0.617021 (-190 2110);
PAINT ORANGE (-190 2110);
FORCEPROP 2 LASTPIN (-200 2050) $PN 172
J 0
(-190 2060);
DISPLAY 0.617021 (-190 2060);
PAINT ORANGE (-190 2060);
FORCEPROP 2 LASTPIN (-200 2000) $PN 27
J 0
(-190 2010);
DISPLAY 0.617021 (-190 2010);
PAINT ORANGE (-190 2010);
FORCEPROP 2 LASTPIN (-200 1950) $PN 166
J 0
(-190 1960);
DISPLAY 0.617021 (-190 1960);
PAINT ORANGE (-190 1960);
FORCEPROP 2 LASTPIN (-200 1900) $PN 21
J 0
(-190 1910);
DISPLAY 0.617021 (-190 1910);
PAINT ORANGE (-190 1910);
FORCEPROP 2 LASTPIN (-200 1850) $PN 159
J 0
(-190 1860);
DISPLAY 0.617021 (-190 1860);
PAINT ORANGE (-190 1860);
FORCEPROP 2 LASTPIN (-200 1800) $PN 14
J 0
(-190 1810);
DISPLAY 0.617021 (-190 1810);
PAINT ORANGE (-190 1810);
FORCEPROP 2 LASTPIN (-200 1750) $PN 168
J 0
(-190 1760);
DISPLAY 0.617021 (-190 1760);
PAINT ORANGE (-190 1760);
FORCEPROP 2 LASTPIN (-200 1700) $PN 23
J 0
(-190 1710);
DISPLAY 0.617021 (-190 1710);
PAINT ORANGE (-190 1710);
FORCEPROP 2 LASTPIN (-200 1650) $PN 161
J 0
(-190 1660);
DISPLAY 0.617021 (-190 1660);
PAINT ORANGE (-190 1660);
FORCEPROP 2 LASTPIN (-200 1600) $PN 16
J 0
(-190 1610);
DISPLAY 0.617021 (-190 1610);
PAINT ORANGE (-190 1610);
FORCEPROP 2 LASTPIN (-200 1550) $PN 155
J 0
(-190 1560);
DISPLAY 0.617021 (-190 1560);
PAINT ORANGE (-190 1560);
FORCEPROP 2 LASTPIN (-200 1500) $PN 10
J 0
(-190 1510);
DISPLAY 0.617021 (-190 1510);
PAINT ORANGE (-190 1510);
FORCEPROP 2 LASTPIN (-200 1450) $PN 148
J 0
(-190 1460);
DISPLAY 0.617021 (-190 1460);
PAINT ORANGE (-190 1460);
FORCEPROP 2 LASTPIN (-200 1400) $PN 3
J 0
(-190 1410);
DISPLAY 0.617021 (-190 1410);
PAINT ORANGE (-190 1410);
FORCEPROP 2 LASTPIN (-200 1350) $PN 157
J 0
(-190 1360);
DISPLAY 0.617021 (-190 1360);
PAINT ORANGE (-190 1360);
FORCEPROP 2 LASTPIN (-200 1300) $PN 12
J 0
(-190 1310);
DISPLAY 0.617021 (-190 1310);
PAINT ORANGE (-190 1310);
FORCEPROP 2 LASTPIN (-200 1250) $PN 150
J 0
(-190 1260);
DISPLAY 0.617021 (-190 1260);
PAINT ORANGE (-190 1260);
FORCEPROP 2 LASTPIN (-200 1200) $PN 5
J 0
(-190 1210);
DISPLAY 0.617021 (-190 1210);
PAINT ORANGE (-190 1210);
FORCEPROP 2 LASTPIN (-1200 2600) $PN 203
J 2
(-1210 2610);
DISPLAY 0.617021 (-1210 2610);
PAINT ORANGE (-1210 2610);
FORCEPROP 2 LASTPIN (-1200 2550) $PN 60
J 2
(-1210 2560);
DISPLAY 0.617021 (-1210 2560);
PAINT ORANGE (-1210 2560);
FORCEPROP 2 LASTPIN (-1200 3150) $PN 218
J 2
(-1210 3160);
DISPLAY 0.617021 (-1210 3160);
PAINT ORANGE (-1210 3160);
FORCEPROP 2 LASTPIN (-1200 3100) $PN 219
J 2
(-1210 3110);
DISPLAY 0.617021 (-1210 3110);
PAINT ORANGE (-1210 3110);
FORCEPROP 2 LASTPIN (-1200 3050) $PN 74
J 2
(-1210 3060);
DISPLAY 0.617021 (-1210 3060);
PAINT ORANGE (-1210 3060);
FORCEPROP 2 LASTPIN (-1200 3000) $PN 75
J 2
(-1210 3010);
DISPLAY 0.617021 (-1210 3010);
PAINT ORANGE (-1210 3010);
FORCEPROP 2 LASTPIN (-1200 2300) $PN 199
J 2
(-1210 2310);
DISPLAY 0.617021 (-1210 2310);
PAINT ORANGE (-1210 2310);
FORCEPROP 2 LASTPIN (-1200 2250) $PN 54
J 2
(-1210 2260);
DISPLAY 0.617021 (-1210 2260);
PAINT ORANGE (-1210 2260);
FORCEPROP 2 LASTPIN (-1200 2200) $PN 192
J 2
(-1210 2210);
DISPLAY 0.617021 (-1210 2210);
PAINT ORANGE (-1210 2210);
FORCEPROP 2 LASTPIN (-1200 2150) $PN 47
J 2
(-1210 2160);
DISPLAY 0.617021 (-1210 2160);
PAINT ORANGE (-1210 2160);
FORCEPROP 2 LASTPIN (-1200 2100) $PN 201
J 2
(-1210 2110);
DISPLAY 0.617021 (-1210 2110);
PAINT ORANGE (-1210 2110);
FORCEPROP 2 LASTPIN (-1200 2050) $PN 56
J 2
(-1210 2060);
DISPLAY 0.617021 (-1210 2060);
PAINT ORANGE (-1210 2060);
FORCEPROP 2 LASTPIN (-1200 2000) $PN 194
J 2
(-1210 2010);
DISPLAY 0.617021 (-1210 2010);
PAINT ORANGE (-1210 2010);
FORCEPROP 2 LASTPIN (-1200 1950) $PN 49
J 2
(-1210 1960);
DISPLAY 0.617021 (-1210 1960);
PAINT ORANGE (-1210 1960);
FORCEPROP 2 LASTPIN (-1200 2900) $PN 235
J 2
(-1210 2910);
DISPLAY 0.617021 (-1210 2910);
PAINT ORANGE (-1210 2910);
FORCEPROP 2 LASTPIN (-1200 3300) $PN 207
J 2
(-1210 3310);
DISPLAY 0.617021 (-1210 3310);
PAINT ORANGE (-1210 3310);
FORCEPROP 2 LASTPIN (-1200 3250) $PN 63
J 2
(-1210 3260);
DISPLAY 0.617021 (-1210 3260);
PAINT ORANGE (-1210 3260);
FORCEPROP 2 LASTPIN (-1200 3400) $PN 224
J 2
(-1210 3410);
DISPLAY 0.617021 (-1210 3410);
PAINT ORANGE (-1210 3410);
FORCEPROP 2 LASTPIN (-1200 3350) $PN 81
J 2
(-1210 3360);
DISPLAY 0.617021 (-1210 3360);
PAINT ORANGE (-1210 3360);
FORCEPROP 2 LASTPIN (-1200 1700) $PN 208
J 2
(-1210 1710);
DISPLAY 0.617021 (-1210 1710);
PAINT ORANGE (-1210 1710);
FORCEPROP 2 LASTPIN (-1200 1650) $PN 62
J 2
(-1210 1660);
DISPLAY 0.617021 (-1210 1660);
PAINT ORANGE (-1210 1660);
FORCEPROP 2 LASTPIN (-1200 4350) $PN 234
J 2
(-1210 4360);
DISPLAY 0.617021 (-1210 4360);
PAINT ORANGE (-1210 4360);
FORCEPROP 2 LASTPIN (-1200 4300) $PN 82
J 2
(-1210 4310);
DISPLAY 0.617021 (-1210 4310);
PAINT ORANGE (-1210 4310);
FORCEPROP 2 LASTPIN (-1200 4250) $PN 86
J 2
(-1210 4260);
DISPLAY 0.617021 (-1210 4260);
PAINT ORANGE (-1210 4260);
FORCEPROP 2 LASTPIN (-1200 4200) $PN 228
J 2
(-1210 4210);
DISPLAY 0.617021 (-1210 4210);
PAINT ORANGE (-1210 4210);
FORCEPROP 2 LASTPIN (-1200 4150) $PN 232
J 2
(-1210 4160);
DISPLAY 0.617021 (-1210 4160);
PAINT ORANGE (-1210 4160);
FORCEPROP 2 LASTPIN (-1200 4100) $PN 65
J 2
(-1210 4110);
DISPLAY 0.617021 (-1210 4110);
PAINT ORANGE (-1210 4110);
FORCEPROP 2 LASTPIN (-1200 4050) $PN 210
J 2
(-1210 4060);
DISPLAY 0.617021 (-1210 4060);
PAINT ORANGE (-1210 4060);
FORCEPROP 2 LASTPIN (-1200 4000) $PN 225
J 2
(-1210 4010);
DISPLAY 0.617021 (-1210 4010);
PAINT ORANGE (-1210 4010);
FORCEPROP 2 LASTPIN (-1200 3950) $PN 66
J 2
(-1210 3960);
DISPLAY 0.617021 (-1210 3960);
PAINT ORANGE (-1210 3960);
FORCEPROP 2 LASTPIN (-1200 3900) $PN 68
J 2
(-1210 3910);
DISPLAY 0.617021 (-1210 3910);
PAINT ORANGE (-1210 3910);
FORCEPROP 2 LASTPIN (-1200 3850) $PN 211
J 2
(-1210 3860);
DISPLAY 0.617021 (-1210 3860);
PAINT ORANGE (-1210 3860);
FORCEPROP 2 LASTPIN (-1200 3800) $PN 69
J 2
(-1210 3810);
DISPLAY 0.617021 (-1210 3810);
PAINT ORANGE (-1210 3810);
FORCEPROP 2 LASTPIN (-1200 3750) $PN 213
J 2
(-1210 3760);
DISPLAY 0.617021 (-1210 3760);
PAINT ORANGE (-1210 3760);
FORCEPROP 2 LASTPIN (-1200 3700) $PN 214
J 2
(-1210 3710);
DISPLAY 0.617021 (-1210 3710);
PAINT ORANGE (-1210 3710);
FORCEPROP 2 LASTPIN (-1200 3650) $PN 71
J 2
(-1210 3660);
DISPLAY 0.617021 (-1210 3660);
PAINT ORANGE (-1210 3660);
FORCEPROP 2 LASTPIN (-1200 3600) $PN 216
J 2
(-1210 3610);
DISPLAY 0.617021 (-1210 3610);
PAINT ORANGE (-1210 3610);
FORCEPROP 2 LASTPIN (-1200 3550) $PN 72
J 2
(-1210 3560);
DISPLAY 0.617021 (-1210 3560);
PAINT ORANGE (-1210 3560);
FORCEPROP 2 LASTPIN (-1200 3500) $PN 79
J 2
(-1210 3510);
DISPLAY 0.617021 (-1210 3510);
PAINT ORANGE (-1210 3510);
FORCEPROP 1 LAST PACK_TYPE PIP
J 0
(-1150 4650);
PAINT SKYBLUE (-1150 4650);
DISPLAY INVISIBLE (-1150 4650);
FORCEPROP 2 LAST BOM_COST MEM
J 0
(-700 2700);
PAINT ORANGE (-700 2700);
DISPLAY INVISIBLE (-700 2700);
FORCEPROP 2 LAST CDS_LIB mstr_sconn
J 0
(-700 2700);
PAINT ORANGE (-700 2700);
DISPLAY INVISIBLE (-700 2700);
FORCEPROP 2 LAST SEC_TYPE PIP
J 0
(-1150 4650);
DISPLAY 1.021277 (-1150 4650);
PAINT ORANGE (-1150 4650);
DISPLAY INVISIBLE (-1150 4650);
FORCEPROP 2 LAST SEC 1
J 0
(-1150 4650);
DISPLAY 0.680851 (-1150 4650);
PAINT MONO (-1150 4650);
DISPLAY INVISIBLE (-1150 4650);
FORCEPROP 2 LAST CDS_LOCATION J6T1
J 0
(-1150 4600);
DISPLAY 0.617021 (-1150 4600);
PAINT AQUA (-1150 4600);
DISPLAY INVISIBLE (-1150 4600);
FORCEPROP 1 LAST PATH I13
J 0
(-700 4550);
PAINT GREEN (-700 4550);
DISPLAY INVISIBLE (-700 4550);
FORCEPROP 2 LAST ROOM DDR4_CH_A
J 0
(-700 2700);
PAINT ORANGE (-700 2700);
DISPLAY INVISIBLE (-700 2700);
FORCEADD TAP..6
R 2
(100 4100);
FORCEPROP 3 LASTPIN (50 4100) SIG_NAME M_A_DQ<58>
J 0
(60 4110);
DISPLAY 0.659574 (60 4110);
PAINT MONO (60 4110);
DISPLAY INVISIBLE (60 4110);
FORCEPROP 1 LASTPIN (50 4100) BN 58
J 2
(100 4110);
DISPLAY 0.617021 (100 4110);
PAINT PINK (100 4110);
FORCEPROP 2 LAST CDS_LIB mstr_standard
J 2
(100 4100);
DISPLAY 0.787234 (100 4100);
PAINT MONO (100 4100);
DISPLAY INVISIBLE (100 4100);
FORCEPROP 1 LAST BODY_TYPE PLUMBING
J 2
(100 4050);
DISPLAY 1.234043 (100 4050);
PAINT GREEN (100 4050);
DISPLAY INVISIBLE (100 4050);
FORCEPROP 1 LAST HDL_TAP TRUE
J 2
(-225 3975);
DISPLAY 1.234043 (-225 3975);
PAINT GREEN (-225 3975);
DISPLAY INVISIBLE (-225 3975);
FORCEPROP 1 LAST PATH I130
J 2
(102 4100);
DISPLAY 0.872340 (102 4100);
PAINT GREEN (102 4100);
DISPLAY INVISIBLE (102 4100);
FORCEADD TAP..6
R 2
(100 4150);
FORCEPROP 3 LASTPIN (50 4150) SIG_NAME M_A_DQ<59>
J 0
(60 4160);
DISPLAY 0.659574 (60 4160);
PAINT MONO (60 4160);
DISPLAY INVISIBLE (60 4160);
FORCEPROP 1 LASTPIN (50 4150) BN 59
J 2
(100 4160);
DISPLAY 0.617021 (100 4160);
PAINT PINK (100 4160);
FORCEPROP 2 LAST CDS_LIB mstr_standard
J 2
(100 4150);
DISPLAY 0.787234 (100 4150);
PAINT MONO (100 4150);
DISPLAY INVISIBLE (100 4150);
FORCEPROP 1 LAST BODY_TYPE PLUMBING
J 2
(100 4100);
DISPLAY 1.234043 (100 4100);
PAINT GREEN (100 4100);
DISPLAY INVISIBLE (100 4100);
FORCEPROP 1 LAST HDL_TAP TRUE
J 2
(-225 4025);
DISPLAY 1.234043 (-225 4025);
PAINT GREEN (-225 4025);
DISPLAY INVISIBLE (-225 4025);
FORCEPROP 1 LAST PATH I131
J 2
(102 4150);
DISPLAY 0.872340 (102 4150);
PAINT GREEN (102 4150);
DISPLAY INVISIBLE (102 4150);
FORCEADD TAP..6
R 2
(100 4200);
FORCEPROP 3 LASTPIN (50 4200) SIG_NAME M_A_DQ<60>
J 0
(60 4210);
DISPLAY 0.659574 (60 4210);
PAINT MONO (60 4210);
DISPLAY INVISIBLE (60 4210);
FORCEPROP 1 LASTPIN (50 4200) BN 60
J 2
(100 4210);
DISPLAY 0.617021 (100 4210);
PAINT PINK (100 4210);
FORCEPROP 2 LAST CDS_LIB mstr_standard
J 2
(100 4200);
DISPLAY 0.787234 (100 4200);
PAINT MONO (100 4200);
DISPLAY INVISIBLE (100 4200);
FORCEPROP 1 LAST BODY_TYPE PLUMBING
J 2
(100 4150);
DISPLAY 1.234043 (100 4150);
PAINT GREEN (100 4150);
DISPLAY INVISIBLE (100 4150);
FORCEPROP 1 LAST HDL_TAP TRUE
J 2
(-225 4075);
DISPLAY 1.234043 (-225 4075);
PAINT GREEN (-225 4075);
DISPLAY INVISIBLE (-225 4075);
FORCEPROP 1 LAST PATH I132
J 2
(102 4200);
DISPLAY 0.872340 (102 4200);
PAINT GREEN (102 4200);
DISPLAY INVISIBLE (102 4200);
FORCEADD TAP..6
R 2
(100 4300);
FORCEPROP 3 LASTPIN (50 4300) SIG_NAME M_A_DQ<62>
J 0
(60 4310);
DISPLAY 0.659574 (60 4310);
PAINT MONO (60 4310);
DISPLAY INVISIBLE (60 4310);
FORCEPROP 1 LASTPIN (50 4300) BN 62
J 2
(100 4310);
DISPLAY 0.617021 (100 4310);
PAINT PINK (100 4310);
FORCEPROP 2 LAST CDS_LIB mstr_standard
J 2
(100 4300);
DISPLAY 0.787234 (100 4300);
PAINT MONO (100 4300);
DISPLAY INVISIBLE (100 4300);
FORCEPROP 1 LAST BODY_TYPE PLUMBING
J 2
(100 4250);
DISPLAY 1.234043 (100 4250);
PAINT GREEN (100 4250);
DISPLAY INVISIBLE (100 4250);
FORCEPROP 1 LAST HDL_TAP TRUE
J 2
(-225 4175);
DISPLAY 1.234043 (-225 4175);
PAINT GREEN (-225 4175);
DISPLAY INVISIBLE (-225 4175);
FORCEPROP 1 LAST PATH I133
J 2
(102 4300);
DISPLAY 0.872340 (102 4300);
PAINT GREEN (102 4300);
DISPLAY INVISIBLE (102 4300);
FORCEADD TAP..6
R 2
(100 4250);
FORCEPROP 3 LASTPIN (50 4250) SIG_NAME M_A_DQ<61>
J 0
(60 4260);
DISPLAY 0.659574 (60 4260);
PAINT MONO (60 4260);
DISPLAY INVISIBLE (60 4260);
FORCEPROP 1 LASTPIN (50 4250) BN 61
J 2
(100 4260);
DISPLAY 0.617021 (100 4260);
PAINT PINK (100 4260);
FORCEPROP 2 LAST CDS_LIB mstr_standard
J 2
(100 4250);
DISPLAY 0.787234 (100 4250);
PAINT MONO (100 4250);
DISPLAY INVISIBLE (100 4250);
FORCEPROP 1 LAST BODY_TYPE PLUMBING
J 2
(100 4200);
DISPLAY 1.234043 (100 4200);
PAINT GREEN (100 4200);
DISPLAY INVISIBLE (100 4200);
FORCEPROP 1 LAST HDL_TAP TRUE
J 2
(-225 4125);
DISPLAY 1.234043 (-225 4125);
PAINT GREEN (-225 4125);
DISPLAY INVISIBLE (-225 4125);
FORCEPROP 1 LAST PATH I134
J 2
(102 4250);
DISPLAY 0.872340 (102 4250);
PAINT GREEN (102 4250);
DISPLAY INVISIBLE (102 4250);
FORCEADD TAP..6
R 2
(100 4350);
FORCEPROP 3 LASTPIN (50 4350) SIG_NAME M_A_DQ<63>
J 0
(60 4360);
DISPLAY 0.659574 (60 4360);
PAINT MONO (60 4360);
DISPLAY INVISIBLE (60 4360);
FORCEPROP 1 LASTPIN (50 4350) BN 63
J 2
(100 4360);
DISPLAY 0.617021 (100 4360);
PAINT PINK (100 4360);
FORCEPROP 2 LAST CDS_LIB mstr_standard
J 2
(100 4350);
DISPLAY 0.787234 (100 4350);
PAINT MONO (100 4350);
DISPLAY INVISIBLE (100 4350);
FORCEPROP 1 LAST BODY_TYPE PLUMBING
J 2
(100 4300);
DISPLAY 1.234043 (100 4300);
PAINT GREEN (100 4300);
DISPLAY INVISIBLE (100 4300);
FORCEPROP 1 LAST HDL_TAP TRUE
J 2
(-225 4225);
DISPLAY 1.234043 (-225 4225);
PAINT GREEN (-225 4225);
DISPLAY INVISIBLE (-225 4225);
FORCEPROP 1 LAST PATH I135
J 2
(102 4350);
DISPLAY 0.872340 (102 4350);
PAINT GREEN (102 4350);
DISPLAY INVISIBLE (102 4350);
FORCEADD OFFPAGE..3
(700 4400);
FORCEPROP 2 LAST $XR0 23 
J 0
(914 4400);
DISPLAY 0.638298 (914 4400);
PAINT MONO (914 4400);
FORCEPROP 2 LAST $XR1 43 
J 0
(1004 4400);
DISPLAY 0.638298 (1004 4400);
PAINT MONO (1004 4400);
FORCEPROP 2 LAST CDS_LIB mstr_standard
J 0
(700 4400);
DISPLAY 0.787234 (700 4400);
PAINT MONO (700 4400);
DISPLAY INVISIBLE (700 4400);
FORCEPROP 1 LAST OFFPAGE TRUE
J 0
(1025 4275);
DISPLAY 0.936170 (1025 4275);
PAINT GREEN (1025 4275);
DISPLAY INVISIBLE (1025 4275);
FORCEPROP 1 LAST COMMENT_BODY TRUE
J 0
(650 4300);
DISPLAY 0.936170 (650 4300);
PAINT GREEN (650 4300);
DISPLAY INVISIBLE (650 4300);
FORCEPROP 2 LAST PATH I136
J 0
(925 4450);
DISPLAY 1.021277 (925 4450);
PAINT ORANGE (925 4450);
DISPLAY INVISIBLE (925 4450);
FORCEADD GND..1
R 2
(2750 1100);
FORCEPROP 3 LASTPIN (2750 1150) SIG_NAME GND\g
J 0
(2760 1160);
DISPLAY 0.659574 (2760 1160);
PAINT MONO (2760 1160);
DISPLAY INVISIBLE (2760 1160);
FORCEPROP 1 LAST VOLTAGE 0
J 0
(2750 1100);
PAINT SKYBLUE (2750 1100);
DISPLAY INVISIBLE (2750 1100);
FORCEPROP 2 LAST BOM_COST MEM
J 0
(2750 1105);
PAINT ORANGE (2750 1105);
DISPLAY INVISIBLE (2750 1105);
FORCEPROP 2 LAST CDS_LIB mstr_symbols
J 0
(2750 1100);
DISPLAY 0.787234 (2750 1100);
PAINT MONO (2750 1100);
DISPLAY INVISIBLE (2750 1100);
FORCEPROP 1 LAST SIZE 1B
J 2
(2675 1050);
DISPLAY 1.170213 (2675 1050);
PAINT GREEN (2675 1050);
DISPLAY INVISIBLE (2675 1050);
FORCEPROP 1 LAST BODY_TYPE PLUMBING
J 2
(2795 1057);
DISPLAY 0.340426 (2795 1057);
PAINT GREEN (2795 1057);
DISPLAY INVISIBLE (2795 1057);
FORCEPROP 1 LAST PATH I138
J 2
(2675 1100);
DISPLAY 0.872340 (2675 1100);
PAINT AQUA (2675 1100);
DISPLAY INVISIBLE (2675 1100);
FORCEPROP 2 LAST ROOM DDR4_CH_A
J 0
(2750 1105);
PAINT ORANGE (2750 1105);
DISPLAY INVISIBLE (2750 1105);
FORCEPROP 1 LAST HDL_POWER GND
J 2
(2750 1250);
DISPLAY 0.553191 (2750 1250);
PAINT GREEN (2750 1250);
DISPLAY INVISIBLE (2750 1250);
FORCEADD SCONN288_H44441003..3
(3450 2400);
FORCEPROP 1 LAST LOCATION J6T1
J 0
(3000 3800);
DISPLAY 0.617021 (3000 3800);
PAINT AQUA (3000 3800);
FORCEPROP 1 LAST PART_NUMBER H44441-003
J 0
(3000 1050);
DISPLAY 0.617021 (3000 1050);
PAINT BLUE (3000 1050);
FORCEPROP 1 LAST MATERIAL SCONN
J 0
(3000 3750);
DISPLAY 0.617021 (3000 3750);
PAINT SKYBLUE (3000 3750);
FORCEPROP 2 LASTPIN (2950 3550) $PN 2
J 2
(2940 3560);
DISPLAY 0.617021 (2940 3560);
PAINT ORANGE (2940 3560);
FORCEPROP 2 LASTPIN (2950 3500) $PN 4
J 2
(2940 3510);
DISPLAY 0.617021 (2940 3510);
PAINT ORANGE (2940 3510);
FORCEPROP 2 LASTPIN (2950 3450) $PN 6
J 2
(2940 3460);
DISPLAY 0.617021 (2940 3460);
PAINT ORANGE (2940 3460);
FORCEPROP 2 LASTPIN (2950 3400) $PN 9
J 2
(2940 3410);
DISPLAY 0.617021 (2940 3410);
PAINT ORANGE (2940 3410);
FORCEPROP 2 LASTPIN (2950 3350) $PN 11
J 2
(2940 3360);
DISPLAY 0.617021 (2940 3360);
PAINT ORANGE (2940 3360);
FORCEPROP 2 LASTPIN (2950 3300) $PN 13
J 2
(2940 3310);
DISPLAY 0.617021 (2940 3310);
PAINT ORANGE (2940 3310);
FORCEPROP 2 LASTPIN (2950 3250) $PN 15
J 2
(2940 3260);
DISPLAY 0.617021 (2940 3260);
PAINT ORANGE (2940 3260);
FORCEPROP 2 LASTPIN (2950 3200) $PN 17
J 2
(2940 3210);
DISPLAY 0.617021 (2940 3210);
PAINT ORANGE (2940 3210);
FORCEPROP 2 LASTPIN (2950 3150) $PN 20
J 2
(2940 3160);
DISPLAY 0.617021 (2940 3160);
PAINT ORANGE (2940 3160);
FORCEPROP 2 LASTPIN (2950 3100) $PN 22
J 2
(2940 3110);
DISPLAY 0.617021 (2940 3110);
PAINT ORANGE (2940 3110);
FORCEPROP 2 LASTPIN (2950 3050) $PN 24
J 2
(2940 3060);
DISPLAY 0.617021 (2940 3060);
PAINT ORANGE (2940 3060);
FORCEPROP 2 LASTPIN (2950 3000) $PN 26
J 2
(2940 3010);
DISPLAY 0.617021 (2940 3010);
PAINT ORANGE (2940 3010);
FORCEPROP 2 LASTPIN (2950 2950) $PN 28
J 2
(2940 2960);
DISPLAY 0.617021 (2940 2960);
PAINT ORANGE (2940 2960);
FORCEPROP 2 LASTPIN (2950 2900) $PN 31
J 2
(2940 2910);
DISPLAY 0.617021 (2940 2910);
PAINT ORANGE (2940 2910);
FORCEPROP 2 LASTPIN (2950 2850) $PN 33
J 2
(2940 2860);
DISPLAY 0.617021 (2940 2860);
PAINT ORANGE (2940 2860);
FORCEPROP 2 LASTPIN (2950 2800) $PN 35
J 2
(2940 2810);
DISPLAY 0.617021 (2940 2810);
PAINT ORANGE (2940 2810);
FORCEPROP 2 LASTPIN (2950 2750) $PN 37
J 2
(2940 2760);
DISPLAY 0.617021 (2940 2760);
PAINT ORANGE (2940 2760);
FORCEPROP 2 LASTPIN (2950 2700) $PN 39
J 2
(2940 2710);
DISPLAY 0.617021 (2940 2710);
PAINT ORANGE (2940 2710);
FORCEPROP 2 LASTPIN (2950 2650) $PN 42
J 2
(2940 2660);
DISPLAY 0.617021 (2940 2660);
PAINT ORANGE (2940 2660);
FORCEPROP 2 LASTPIN (2950 2600) $PN 44
J 2
(2940 2610);
DISPLAY 0.617021 (2940 2610);
PAINT ORANGE (2940 2610);
FORCEPROP 2 LASTPIN (2950 2550) $PN 46
J 2
(2940 2560);
DISPLAY 0.617021 (2940 2560);
PAINT ORANGE (2940 2560);
FORCEPROP 2 LASTPIN (2950 2500) $PN 48
J 2
(2940 2510);
DISPLAY 0.617021 (2940 2510);
PAINT ORANGE (2940 2510);
FORCEPROP 2 LASTPIN (2950 2450) $PN 50
J 2
(2940 2460);
DISPLAY 0.617021 (2940 2460);
PAINT ORANGE (2940 2460);
FORCEPROP 2 LASTPIN (2950 2400) $PN 53
J 2
(2940 2410);
DISPLAY 0.617021 (2940 2410);
PAINT ORANGE (2940 2410);
FORCEPROP 2 LASTPIN (2950 2350) $PN 55
J 2
(2940 2360);
DISPLAY 0.617021 (2940 2360);
PAINT ORANGE (2940 2360);
FORCEPROP 2 LASTPIN (2950 2300) $PN 57
J 2
(2940 2310);
DISPLAY 0.617021 (2940 2310);
PAINT ORANGE (2940 2310);
FORCEPROP 2 LASTPIN (2950 2250) $PN 94
J 2
(2940 2260);
DISPLAY 0.617021 (2940 2260);
PAINT ORANGE (2940 2260);
FORCEPROP 2 LASTPIN (2950 2200) $PN 96
J 2
(2940 2210);
DISPLAY 0.617021 (2940 2210);
PAINT ORANGE (2940 2210);
FORCEPROP 2 LASTPIN (2950 2150) $PN 98
J 2
(2940 2160);
DISPLAY 0.617021 (2940 2160);
PAINT ORANGE (2940 2160);
FORCEPROP 2 LASTPIN (2950 2100) $PN 101
J 2
(2940 2110);
DISPLAY 0.617021 (2940 2110);
PAINT ORANGE (2940 2110);
FORCEPROP 2 LASTPIN (2950 2050) $PN 103
J 2
(2940 2060);
DISPLAY 0.617021 (2940 2060);
PAINT ORANGE (2940 2060);
FORCEPROP 2 LASTPIN (2950 2000) $PN 105
J 2
(2940 2010);
DISPLAY 0.617021 (2940 2010);
PAINT ORANGE (2940 2010);
FORCEPROP 2 LASTPIN (2950 1950) $PN 107
J 2
(2940 1960);
DISPLAY 0.617021 (2940 1960);
PAINT ORANGE (2940 1960);
FORCEPROP 2 LASTPIN (2950 1900) $PN 109
J 2
(2940 1910);
DISPLAY 0.617021 (2940 1910);
PAINT ORANGE (2940 1910);
FORCEPROP 2 LASTPIN (2950 1850) $PN 112
J 2
(2940 1860);
DISPLAY 0.617021 (2940 1860);
PAINT ORANGE (2940 1860);
FORCEPROP 2 LASTPIN (2950 1800) $PN 114
J 2
(2940 1810);
DISPLAY 0.617021 (2940 1810);
PAINT ORANGE (2940 1810);
FORCEPROP 2 LASTPIN (2950 1750) $PN 116
J 2
(2940 1760);
DISPLAY 0.617021 (2940 1760);
PAINT ORANGE (2940 1760);
FORCEPROP 2 LASTPIN (2950 1700) $PN 118
J 2
(2940 1710);
DISPLAY 0.617021 (2940 1710);
PAINT ORANGE (2940 1710);
FORCEPROP 2 LASTPIN (2950 1650) $PN 120
J 2
(2940 1660);
DISPLAY 0.617021 (2940 1660);
PAINT ORANGE (2940 1660);
FORCEPROP 2 LASTPIN (2950 1600) $PN 123
J 2
(2940 1610);
DISPLAY 0.617021 (2940 1610);
PAINT ORANGE (2940 1610);
FORCEPROP 2 LASTPIN (2950 1550) $PN 125
J 2
(2940 1560);
DISPLAY 0.617021 (2940 1560);
PAINT ORANGE (2940 1560);
FORCEPROP 2 LASTPIN (2950 1500) $PN 127
J 2
(2940 1510);
DISPLAY 0.617021 (2940 1510);
PAINT ORANGE (2940 1510);
FORCEPROP 2 LASTPIN (2950 1450) $PN 129
J 2
(2940 1460);
DISPLAY 0.617021 (2940 1460);
PAINT ORANGE (2940 1460);
FORCEPROP 2 LASTPIN (2950 1400) $PN 131
J 2
(2940 1410);
DISPLAY 0.617021 (2940 1410);
PAINT ORANGE (2940 1410);
FORCEPROP 2 LASTPIN (2950 1350) $PN 134
J 2
(2940 1360);
DISPLAY 0.617021 (2940 1360);
PAINT ORANGE (2940 1360);
FORCEPROP 2 LASTPIN (2950 1300) $PN 136
J 2
(2940 1310);
DISPLAY 0.617021 (2940 1310);
PAINT ORANGE (2940 1310);
FORCEPROP 2 LASTPIN (2950 1250) $PN 138
J 2
(2940 1260);
DISPLAY 0.617021 (2940 1260);
PAINT ORANGE (2940 1260);
FORCEPROP 2 LASTPIN (3950 3550) $PN 147
J 0
(3960 3560);
DISPLAY 0.617021 (3960 3560);
PAINT ORANGE (3960 3560);
FORCEPROP 2 LASTPIN (3950 3500) $PN 149
J 0
(3960 3510);
DISPLAY 0.617021 (3960 3510);
PAINT ORANGE (3960 3510);
FORCEPROP 2 LASTPIN (3950 3450) $PN 151
J 0
(3960 3460);
DISPLAY 0.617021 (3960 3460);
PAINT ORANGE (3960 3460);
FORCEPROP 2 LASTPIN (3950 3400) $PN 154
J 0
(3960 3410);
DISPLAY 0.617021 (3960 3410);
PAINT ORANGE (3960 3410);
FORCEPROP 2 LASTPIN (3950 3350) $PN 156
J 0
(3960 3360);
DISPLAY 0.617021 (3960 3360);
PAINT ORANGE (3960 3360);
FORCEPROP 2 LASTPIN (3950 3300) $PN 158
J 0
(3960 3310);
DISPLAY 0.617021 (3960 3310);
PAINT ORANGE (3960 3310);
FORCEPROP 2 LASTPIN (3950 3250) $PN 160
J 0
(3960 3260);
DISPLAY 0.617021 (3960 3260);
PAINT ORANGE (3960 3260);
FORCEPROP 2 LASTPIN (3950 3200) $PN 162
J 0
(3960 3210);
DISPLAY 0.617021 (3960 3210);
PAINT ORANGE (3960 3210);
FORCEPROP 2 LASTPIN (3950 3150) $PN 165
J 0
(3960 3160);
DISPLAY 0.617021 (3960 3160);
PAINT ORANGE (3960 3160);
FORCEPROP 2 LASTPIN (3950 3100) $PN 167
J 0
(3960 3110);
DISPLAY 0.617021 (3960 3110);
PAINT ORANGE (3960 3110);
FORCEPROP 2 LASTPIN (3950 3050) $PN 169
J 0
(3960 3060);
DISPLAY 0.617021 (3960 3060);
PAINT ORANGE (3960 3060);
FORCEPROP 2 LASTPIN (3950 3000) $PN 171
J 0
(3960 3010);
DISPLAY 0.617021 (3960 3010);
PAINT ORANGE (3960 3010);
FORCEPROP 2 LASTPIN (3950 2950) $PN 173
J 0
(3960 2960);
DISPLAY 0.617021 (3960 2960);
PAINT ORANGE (3960 2960);
FORCEPROP 2 LASTPIN (3950 2900) $PN 176
J 0
(3960 2910);
DISPLAY 0.617021 (3960 2910);
PAINT ORANGE (3960 2910);
FORCEPROP 2 LASTPIN (3950 2850) $PN 178
J 0
(3960 2860);
DISPLAY 0.617021 (3960 2860);
PAINT ORANGE (3960 2860);
FORCEPROP 2 LASTPIN (3950 2800) $PN 180
J 0
(3960 2810);
DISPLAY 0.617021 (3960 2810);
PAINT ORANGE (3960 2810);
FORCEPROP 2 LASTPIN (3950 2750) $PN 182
J 0
(3960 2760);
DISPLAY 0.617021 (3960 2760);
PAINT ORANGE (3960 2760);
FORCEPROP 2 LASTPIN (3950 2700) $PN 184
J 0
(3960 2710);
DISPLAY 0.617021 (3960 2710);
PAINT ORANGE (3960 2710);
FORCEPROP 2 LASTPIN (3950 2650) $PN 187
J 0
(3960 2660);
DISPLAY 0.617021 (3960 2660);
PAINT ORANGE (3960 2660);
FORCEPROP 2 LASTPIN (3950 2600) $PN 189
J 0
(3960 2610);
DISPLAY 0.617021 (3960 2610);
PAINT ORANGE (3960 2610);
FORCEPROP 2 LASTPIN (3950 2550) $PN 191
J 0
(3960 2560);
DISPLAY 0.617021 (3960 2560);
PAINT ORANGE (3960 2560);
FORCEPROP 2 LASTPIN (3950 2500) $PN 193
J 0
(3960 2510);
DISPLAY 0.617021 (3960 2510);
PAINT ORANGE (3960 2510);
FORCEPROP 2 LASTPIN (3950 2450) $PN 195
J 0
(3960 2460);
DISPLAY 0.617021 (3960 2460);
PAINT ORANGE (3960 2460);
FORCEPROP 2 LASTPIN (3950 2400) $PN 198
J 0
(3960 2410);
DISPLAY 0.617021 (3960 2410);
PAINT ORANGE (3960 2410);
FORCEPROP 2 LASTPIN (3950 2350) $PN 200
J 0
(3960 2360);
DISPLAY 0.617021 (3960 2360);
PAINT ORANGE (3960 2360);
FORCEPROP 2 LASTPIN (3950 2300) $PN 202
J 0
(3960 2310);
DISPLAY 0.617021 (3960 2310);
PAINT ORANGE (3960 2310);
FORCEPROP 2 LASTPIN (3950 2250) $PN 239
J 0
(3960 2260);
DISPLAY 0.617021 (3960 2260);
PAINT ORANGE (3960 2260);
FORCEPROP 2 LASTPIN (3950 2200) $PN 241
J 0
(3960 2210);
DISPLAY 0.617021 (3960 2210);
PAINT ORANGE (3960 2210);
FORCEPROP 2 LASTPIN (3950 2150) $PN 243
J 0
(3960 2160);
DISPLAY 0.617021 (3960 2160);
PAINT ORANGE (3960 2160);
FORCEPROP 2 LASTPIN (3950 2100) $PN 246
J 0
(3960 2110);
DISPLAY 0.617021 (3960 2110);
PAINT ORANGE (3960 2110);
FORCEPROP 2 LASTPIN (3950 2050) $PN 248
J 0
(3960 2060);
DISPLAY 0.617021 (3960 2060);
PAINT ORANGE (3960 2060);
FORCEPROP 2 LASTPIN (3950 2000) $PN 250
J 0
(3960 2010);
DISPLAY 0.617021 (3960 2010);
PAINT ORANGE (3960 2010);
FORCEPROP 2 LASTPIN (3950 1950) $PN 252
J 0
(3960 1960);
DISPLAY 0.617021 (3960 1960);
PAINT ORANGE (3960 1960);
FORCEPROP 2 LASTPIN (3950 1900) $PN 254
J 0
(3960 1910);
DISPLAY 0.617021 (3960 1910);
PAINT ORANGE (3960 1910);
FORCEPROP 2 LASTPIN (3950 1850) $PN 257
J 0
(3960 1860);
DISPLAY 0.617021 (3960 1860);
PAINT ORANGE (3960 1860);
FORCEPROP 2 LASTPIN (3950 1800) $PN 259
J 0
(3960 1810);
DISPLAY 0.617021 (3960 1810);
PAINT ORANGE (3960 1810);
FORCEPROP 2 LASTPIN (3950 1750) $PN 261
J 0
(3960 1760);
DISPLAY 0.617021 (3960 1760);
PAINT ORANGE (3960 1760);
FORCEPROP 2 LASTPIN (3950 1700) $PN 263
J 0
(3960 1710);
DISPLAY 0.617021 (3960 1710);
PAINT ORANGE (3960 1710);
FORCEPROP 2 LASTPIN (3950 1650) $PN 265
J 0
(3960 1660);
DISPLAY 0.617021 (3960 1660);
PAINT ORANGE (3960 1660);
FORCEPROP 2 LASTPIN (3950 1600) $PN 268
J 0
(3960 1610);
DISPLAY 0.617021 (3960 1610);
PAINT ORANGE (3960 1610);
FORCEPROP 2 LASTPIN (3950 1550) $PN 270
J 0
(3960 1560);
DISPLAY 0.617021 (3960 1560);
PAINT ORANGE (3960 1560);
FORCEPROP 2 LASTPIN (3950 1500) $PN 272
J 0
(3960 1510);
DISPLAY 0.617021 (3960 1510);
PAINT ORANGE (3960 1510);
FORCEPROP 2 LASTPIN (3950 1450) $PN 274
J 0
(3960 1460);
DISPLAY 0.617021 (3960 1460);
PAINT ORANGE (3960 1460);
FORCEPROP 2 LASTPIN (3950 1400) $PN 276
J 0
(3960 1410);
DISPLAY 0.617021 (3960 1410);
PAINT ORANGE (3960 1410);
FORCEPROP 2 LASTPIN (3950 1350) $PN 279
J 0
(3960 1360);
DISPLAY 0.617021 (3960 1360);
PAINT ORANGE (3960 1360);
FORCEPROP 2 LASTPIN (3950 1300) $PN 281
J 0
(3960 1310);
DISPLAY 0.617021 (3960 1310);
PAINT ORANGE (3960 1310);
FORCEPROP 2 LASTPIN (3950 1250) $PN 283
J 0
(3960 1260);
DISPLAY 0.617021 (3960 1260);
PAINT ORANGE (3960 1260);
FORCEPROP 1 LAST PACK_TYPE PIP
J 0
(3000 3850);
PAINT SKYBLUE (3000 3850);
DISPLAY INVISIBLE (3000 3850);
FORCEPROP 2 LAST BOM_COST MEM
J 0
(3450 2400);
PAINT ORANGE (3450 2400);
DISPLAY INVISIBLE (3450 2400);
FORCEPROP 2 LAST CDS_LIB mstr_sconn
J 0
(3450 2400);
PAINT ORANGE (3450 2400);
DISPLAY INVISIBLE (3450 2400);
FORCEPROP 2 LAST SEC_TYPE PIP
J 0
(3000 3850);
DISPLAY 1.021277 (3000 3850);
PAINT ORANGE (3000 3850);
DISPLAY INVISIBLE (3000 3850);
FORCEPROP 2 LAST SEC 3
J 0
(3000 3850);
DISPLAY 0.680851 (3000 3850);
PAINT MONO (3000 3850);
DISPLAY INVISIBLE (3000 3850);
FORCEPROP 2 LAST CDS_LOCATION J6T1
J 0
(3000 3800);
DISPLAY 0.617021 (3000 3800);
PAINT AQUA (3000 3800);
DISPLAY INVISIBLE (3000 3800);
FORCEPROP 1 LAST PATH I139
J 0
(3450 3750);
PAINT GREEN (3450 3750);
DISPLAY INVISIBLE (3450 3750);
FORCEPROP 2 LAST ROOM DDR4_CH_A
J 0
(3450 2400);
PAINT ORANGE (3450 2400);
DISPLAY INVISIBLE (3450 2400);
FORCEADD OFFPAGE..1
(-2100 2250);
FORCEPROP 2 LAST $XR0 21 
J 0
(-2321 2250);
DISPLAY 0.638298 (-2321 2250);
PAINT MONO (-2321 2250);
FORCEPROP 2 LAST $XR1 43 
J 0
(-2411 2250);
DISPLAY 0.638298 (-2411 2250);
PAINT MONO (-2411 2250);
FORCEPROP 2 LAST $XR2 45 
J 0
(-2501 2250);
DISPLAY 0.638298 (-2501 2250);
PAINT MONO (-2501 2250);
FORCEPROP 2 LAST $XR3 46 
J 0
(-2591 2250);
DISPLAY 0.638298 (-2591 2250);
PAINT MONO (-2591 2250);
FORCEPROP 2 LAST $XR4 47 
J 0
(-2681 2250);
DISPLAY 0.638298 (-2681 2250);
PAINT MONO (-2681 2250);
FORCEPROP 2 LAST $XR5 48 
J 0
(-2771 2250);
DISPLAY 0.638298 (-2771 2250);
PAINT MONO (-2771 2250);
FORCEPROP 2 LAST CDS_LIB mstr_standard
J 0
(-2100 2250);
DISPLAY 0.787234 (-2100 2250);
PAINT MONO (-2100 2250);
DISPLAY INVISIBLE (-2100 2250);
FORCEPROP 1 LAST OFFPAGE TRUE
J 0
(-1775 2125);
DISPLAY 0.936170 (-1775 2125);
PAINT GREEN (-1775 2125);
DISPLAY INVISIBLE (-1775 2125);
FORCEPROP 1 LAST COMMENT_BODY TRUE
J 0
(-1975 2150);
DISPLAY 0.936170 (-1975 2150);
PAINT GREEN (-1975 2150);
DISPLAY INVISIBLE (-1975 2150);
FORCEPROP 2 LAST PATH I14
J 0
(-2275 2300);
DISPLAY 1.021277 (-2275 2300);
PAINT ORANGE (-2275 2300);
DISPLAY INVISIBLE (-2275 2300);
FORCEADD TAP..6
R 2
(2350 3150);
FORCEPROP 3 LASTPIN (2300 3150) SIG_NAME M_A_DQS_DP<0>
J 0
(2310 3160);
DISPLAY 0.659574 (2310 3160);
PAINT MONO (2310 3160);
DISPLAY INVISIBLE (2310 3160);
FORCEPROP 1 LASTPIN (2300 3150) BN 0
J 2
(2350 3160);
DISPLAY 0.617021 (2350 3160);
PAINT PINK (2350 3160);
FORCEPROP 2 LAST CDS_LIB mstr_standard
J 0
(2350 3150);
DISPLAY 0.787234 (2350 3150);
PAINT MONO (2350 3150);
DISPLAY INVISIBLE (2350 3150);
FORCEPROP 1 LAST BODY_TYPE PLUMBING
J 2
(2350 3100);
DISPLAY 1.234043 (2350 3100);
PAINT GREEN (2350 3100);
DISPLAY INVISIBLE (2350 3100);
FORCEPROP 1 LAST HDL_TAP TRUE
J 2
(2025 3025);
DISPLAY 1.234043 (2025 3025);
PAINT GREEN (2025 3025);
DISPLAY INVISIBLE (2025 3025);
FORCEPROP 1 LAST PATH I142
J 2
(2352 3150);
DISPLAY 0.872340 (2352 3150);
PAINT GREEN (2352 3150);
DISPLAY INVISIBLE (2352 3150);
FORCEADD TAP..6
R 2
(2350 3250);
FORCEPROP 3 LASTPIN (2300 3250) SIG_NAME M_A_DQS_DP<1>
J 0
(2310 3260);
DISPLAY 0.659574 (2310 3260);
PAINT MONO (2310 3260);
DISPLAY INVISIBLE (2310 3260);
FORCEPROP 1 LASTPIN (2300 3250) BN 1
J 2
(2350 3260);
DISPLAY 0.617021 (2350 3260);
PAINT PINK (2350 3260);
FORCEPROP 2 LAST CDS_LIB mstr_standard
J 0
(2350 3250);
DISPLAY 0.787234 (2350 3250);
PAINT MONO (2350 3250);
DISPLAY INVISIBLE (2350 3250);
FORCEPROP 1 LAST BODY_TYPE PLUMBING
J 2
(2350 3200);
DISPLAY 1.234043 (2350 3200);
PAINT GREEN (2350 3200);
DISPLAY INVISIBLE (2350 3200);
FORCEPROP 1 LAST HDL_TAP TRUE
J 2
(2025 3125);
DISPLAY 1.234043 (2025 3125);
PAINT GREEN (2025 3125);
DISPLAY INVISIBLE (2025 3125);
FORCEPROP 1 LAST PATH I143
J 2
(2352 3250);
DISPLAY 0.872340 (2352 3250);
PAINT GREEN (2352 3250);
DISPLAY INVISIBLE (2352 3250);
FORCEADD TAP..6
R 2
(2350 3450);
FORCEPROP 3 LASTPIN (2300 3450) SIG_NAME M_A_DQS_DP<3>
J 0
(2310 3460);
DISPLAY 0.659574 (2310 3460);
PAINT MONO (2310 3460);
DISPLAY INVISIBLE (2310 3460);
FORCEPROP 1 LASTPIN (2300 3450) BN 3
J 2
(2350 3460);
DISPLAY 0.617021 (2350 3460);
PAINT PINK (2350 3460);
FORCEPROP 2 LAST CDS_LIB mstr_standard
J 0
(2350 3450);
DISPLAY 0.787234 (2350 3450);
PAINT MONO (2350 3450);
DISPLAY INVISIBLE (2350 3450);
FORCEPROP 1 LAST BODY_TYPE PLUMBING
J 2
(2350 3400);
DISPLAY 1.234043 (2350 3400);
PAINT GREEN (2350 3400);
DISPLAY INVISIBLE (2350 3400);
FORCEPROP 1 LAST HDL_TAP TRUE
J 2
(2025 3325);
DISPLAY 1.234043 (2025 3325);
PAINT GREEN (2025 3325);
DISPLAY INVISIBLE (2025 3325);
FORCEPROP 1 LAST PATH I144
J 2
(2352 3450);
DISPLAY 0.872340 (2352 3450);
PAINT GREEN (2352 3450);
DISPLAY INVISIBLE (2352 3450);
FORCEADD TAP..6
R 2
(2350 3350);
FORCEPROP 3 LASTPIN (2300 3350) SIG_NAME M_A_DQS_DP<2>
J 0
(2310 3360);
DISPLAY 0.659574 (2310 3360);
PAINT MONO (2310 3360);
DISPLAY INVISIBLE (2310 3360);
FORCEPROP 1 LASTPIN (2300 3350) BN 2
J 2
(2350 3360);
DISPLAY 0.617021 (2350 3360);
PAINT PINK (2350 3360);
FORCEPROP 2 LAST CDS_LIB mstr_standard
J 0
(2350 3350);
DISPLAY 0.787234 (2350 3350);
PAINT MONO (2350 3350);
DISPLAY INVISIBLE (2350 3350);
FORCEPROP 1 LAST BODY_TYPE PLUMBING
J 2
(2350 3300);
DISPLAY 1.234043 (2350 3300);
PAINT GREEN (2350 3300);
DISPLAY INVISIBLE (2350 3300);
FORCEPROP 1 LAST HDL_TAP TRUE
J 2
(2025 3225);
DISPLAY 1.234043 (2025 3225);
PAINT GREEN (2025 3225);
DISPLAY INVISIBLE (2025 3225);
FORCEPROP 1 LAST PATH I145
J 2
(2352 3350);
DISPLAY 0.872340 (2352 3350);
PAINT GREEN (2352 3350);
DISPLAY INVISIBLE (2352 3350);
FORCEADD TAP..6
R 2
(2550 3100);
FORCEPROP 3 LASTPIN (2500 3100) SIG_NAME M_A_DQS_DN<0>
J 0
(2510 3110);
DISPLAY 0.659574 (2510 3110);
PAINT MONO (2510 3110);
DISPLAY INVISIBLE (2510 3110);
FORCEPROP 1 LASTPIN (2500 3100) BN 0
J 2
(2550 3110);
DISPLAY 0.617021 (2550 3110);
PAINT PINK (2550 3110);
FORCEPROP 2 LAST CDS_LIB mstr_standard
J 0
(2550 3100);
DISPLAY 0.787234 (2550 3100);
PAINT MONO (2550 3100);
DISPLAY INVISIBLE (2550 3100);
FORCEPROP 1 LAST BODY_TYPE PLUMBING
J 2
(2550 3050);
DISPLAY 1.234043 (2550 3050);
PAINT GREEN (2550 3050);
DISPLAY INVISIBLE (2550 3050);
FORCEPROP 1 LAST HDL_TAP TRUE
J 2
(2225 2975);
DISPLAY 1.234043 (2225 2975);
PAINT GREEN (2225 2975);
DISPLAY INVISIBLE (2225 2975);
FORCEPROP 1 LAST PATH I146
J 2
(2552 3100);
DISPLAY 0.872340 (2552 3100);
PAINT GREEN (2552 3100);
DISPLAY INVISIBLE (2552 3100);
FORCEADD TAP..6
R 2
(2550 3200);
FORCEPROP 3 LASTPIN (2500 3200) SIG_NAME M_A_DQS_DN<1>
J 0
(2510 3210);
DISPLAY 0.659574 (2510 3210);
PAINT MONO (2510 3210);
DISPLAY INVISIBLE (2510 3210);
FORCEPROP 1 LASTPIN (2500 3200) BN 1
J 2
(2550 3210);
DISPLAY 0.617021 (2550 3210);
PAINT PINK (2550 3210);
FORCEPROP 2 LAST CDS_LIB mstr_standard
J 0
(2550 3200);
DISPLAY 0.787234 (2550 3200);
PAINT MONO (2550 3200);
DISPLAY INVISIBLE (2550 3200);
FORCEPROP 1 LAST BODY_TYPE PLUMBING
J 2
(2550 3150);
DISPLAY 1.234043 (2550 3150);
PAINT GREEN (2550 3150);
DISPLAY INVISIBLE (2550 3150);
FORCEPROP 1 LAST HDL_TAP TRUE
J 2
(2225 3075);
DISPLAY 1.234043 (2225 3075);
PAINT GREEN (2225 3075);
DISPLAY INVISIBLE (2225 3075);
FORCEPROP 1 LAST PATH I147
J 2
(2552 3200);
DISPLAY 0.872340 (2552 3200);
PAINT GREEN (2552 3200);
DISPLAY INVISIBLE (2552 3200);
FORCEADD TAP..6
R 2
(2550 3300);
FORCEPROP 3 LASTPIN (2500 3300) SIG_NAME M_A_DQS_DN<2>
J 0
(2510 3310);
DISPLAY 0.659574 (2510 3310);
PAINT MONO (2510 3310);
DISPLAY INVISIBLE (2510 3310);
FORCEPROP 1 LASTPIN (2500 3300) BN 2
J 2
(2550 3310);
DISPLAY 0.617021 (2550 3310);
PAINT PINK (2550 3310);
FORCEPROP 2 LAST CDS_LIB mstr_standard
J 0
(2550 3300);
DISPLAY 0.787234 (2550 3300);
PAINT MONO (2550 3300);
DISPLAY INVISIBLE (2550 3300);
FORCEPROP 1 LAST BODY_TYPE PLUMBING
J 2
(2550 3250);
DISPLAY 1.234043 (2550 3250);
PAINT GREEN (2550 3250);
DISPLAY INVISIBLE (2550 3250);
FORCEPROP 1 LAST HDL_TAP TRUE
J 2
(2225 3175);
DISPLAY 1.234043 (2225 3175);
PAINT GREEN (2225 3175);
DISPLAY INVISIBLE (2225 3175);
FORCEPROP 1 LAST PATH I148
J 2
(2552 3300);
DISPLAY 0.872340 (2552 3300);
PAINT GREEN (2552 3300);
DISPLAY INVISIBLE (2552 3300);
FORCEADD TAP..6
R 2
(2550 3400);
FORCEPROP 3 LASTPIN (2500 3400) SIG_NAME M_A_DQS_DN<3>
J 0
(2510 3410);
DISPLAY 0.659574 (2510 3410);
PAINT MONO (2510 3410);
DISPLAY INVISIBLE (2510 3410);
FORCEPROP 1 LASTPIN (2500 3400) BN 3
J 2
(2550 3410);
DISPLAY 0.617021 (2550 3410);
PAINT PINK (2550 3410);
FORCEPROP 2 LAST CDS_LIB mstr_standard
J 0
(2550 3400);
DISPLAY 0.787234 (2550 3400);
PAINT MONO (2550 3400);
DISPLAY INVISIBLE (2550 3400);
FORCEPROP 1 LAST BODY_TYPE PLUMBING
J 2
(2550 3350);
DISPLAY 1.234043 (2550 3350);
PAINT GREEN (2550 3350);
DISPLAY INVISIBLE (2550 3350);
FORCEPROP 1 LAST HDL_TAP TRUE
J 2
(2225 3275);
DISPLAY 1.234043 (2225 3275);
PAINT GREEN (2225 3275);
DISPLAY INVISIBLE (2225 3275);
FORCEPROP 1 LAST PATH I149
J 2
(2552 3400);
DISPLAY 0.872340 (2552 3400);
PAINT GREEN (2552 3400);
DISPLAY INVISIBLE (2552 3400);
FORCEADD OFFPAGE..6
(-2100 2350);
FORCEPROP 2 LAST $XR0 23 
J 0
(-2379 2350);
DISPLAY 0.638298 (-2379 2350);
PAINT MONO (-2379 2350);
FORCEPROP 2 LAST $XR1 43 
J 0
(-2469 2350);
DISPLAY 0.638298 (-2469 2350);
PAINT MONO (-2469 2350);
FORCEPROP 2 LAST CDS_LIB mstr_standard
J 0
(-2100 2350);
DISPLAY 0.787234 (-2100 2350);
PAINT MONO (-2100 2350);
DISPLAY INVISIBLE (-2100 2350);
FORCEPROP 1 LAST OFFPAGE TRUE
J 0
(-1775 2225);
DISPLAY 0.936170 (-1775 2225);
PAINT GREEN (-1775 2225);
DISPLAY INVISIBLE (-1775 2225);
FORCEPROP 1 LAST COMMENT_BODY TRUE
J 0
(-2000 2275);
DISPLAY 0.936170 (-2000 2275);
PAINT GREEN (-2000 2275);
DISPLAY INVISIBLE (-2000 2275);
FORCEPROP 2 LAST PATH I15
J 0
(-2375 2400);
DISPLAY 1.021277 (-2375 2400);
PAINT ORANGE (-2375 2400);
DISPLAY INVISIBLE (-2375 2400);
FORCEADD TAP..6
R 2
(2550 3500);
FORCEPROP 3 LASTPIN (2500 3500) SIG_NAME M_A_DQS_DN<4>
J 0
(2510 3510);
DISPLAY 0.659574 (2510 3510);
PAINT MONO (2510 3510);
DISPLAY INVISIBLE (2510 3510);
FORCEPROP 1 LASTPIN (2500 3500) BN 4
J 2
(2550 3510);
DISPLAY 0.617021 (2550 3510);
PAINT PINK (2550 3510);
FORCEPROP 2 LAST CDS_LIB mstr_standard
J 0
(2550 3500);
DISPLAY 0.787234 (2550 3500);
PAINT MONO (2550 3500);
DISPLAY INVISIBLE (2550 3500);
FORCEPROP 1 LAST BODY_TYPE PLUMBING
J 2
(2550 3450);
DISPLAY 1.234043 (2550 3450);
PAINT GREEN (2550 3450);
DISPLAY INVISIBLE (2550 3450);
FORCEPROP 1 LAST HDL_TAP TRUE
J 2
(2225 3375);
DISPLAY 1.234043 (2225 3375);
PAINT GREEN (2225 3375);
DISPLAY INVISIBLE (2225 3375);
FORCEPROP 1 LAST PATH I150
J 2
(2552 3500);
DISPLAY 0.872340 (2552 3500);
PAINT GREEN (2552 3500);
DISPLAY INVISIBLE (2552 3500);
FORCEADD TAP..6
R 2
(2350 3650);
FORCEPROP 3 LASTPIN (2300 3650) SIG_NAME M_A_DQS_DP<5>
J 0
(2310 3660);
DISPLAY 0.659574 (2310 3660);
PAINT MONO (2310 3660);
DISPLAY INVISIBLE (2310 3660);
FORCEPROP 1 LASTPIN (2300 3650) BN 5
J 2
(2350 3660);
DISPLAY 0.617021 (2350 3660);
PAINT PINK (2350 3660);
FORCEPROP 2 LAST CDS_LIB mstr_standard
J 0
(2350 3650);
DISPLAY 0.787234 (2350 3650);
PAINT MONO (2350 3650);
DISPLAY INVISIBLE (2350 3650);
FORCEPROP 1 LAST BODY_TYPE PLUMBING
J 2
(2350 3600);
DISPLAY 1.234043 (2350 3600);
PAINT GREEN (2350 3600);
DISPLAY INVISIBLE (2350 3600);
FORCEPROP 1 LAST HDL_TAP TRUE
J 2
(2025 3525);
DISPLAY 1.234043 (2025 3525);
PAINT GREEN (2025 3525);
DISPLAY INVISIBLE (2025 3525);
FORCEPROP 1 LAST PATH I151
J 2
(2352 3650);
DISPLAY 0.872340 (2352 3650);
PAINT GREEN (2352 3650);
DISPLAY INVISIBLE (2352 3650);
FORCEADD TAP..6
R 2
(2350 3750);
FORCEPROP 3 LASTPIN (2300 3750) SIG_NAME M_A_DQS_DP<6>
J 0
(2310 3760);
DISPLAY 0.659574 (2310 3760);
PAINT MONO (2310 3760);
DISPLAY INVISIBLE (2310 3760);
FORCEPROP 1 LASTPIN (2300 3750) BN 6
J 2
(2350 3760);
DISPLAY 0.617021 (2350 3760);
PAINT PINK (2350 3760);
FORCEPROP 2 LAST CDS_LIB mstr_standard
J 0
(2350 3750);
DISPLAY 0.787234 (2350 3750);
PAINT MONO (2350 3750);
DISPLAY INVISIBLE (2350 3750);
FORCEPROP 1 LAST BODY_TYPE PLUMBING
J 2
(2350 3700);
DISPLAY 1.234043 (2350 3700);
PAINT GREEN (2350 3700);
DISPLAY INVISIBLE (2350 3700);
FORCEPROP 1 LAST HDL_TAP TRUE
J 2
(2025 3625);
DISPLAY 1.234043 (2025 3625);
PAINT GREEN (2025 3625);
DISPLAY INVISIBLE (2025 3625);
FORCEPROP 1 LAST PATH I152
J 2
(2352 3750);
DISPLAY 0.872340 (2352 3750);
PAINT GREEN (2352 3750);
DISPLAY INVISIBLE (2352 3750);
FORCEADD TAP..6
R 2
(2350 3550);
FORCEPROP 3 LASTPIN (2300 3550) SIG_NAME M_A_DQS_DP<4>
J 0
(2310 3560);
DISPLAY 0.659574 (2310 3560);
PAINT MONO (2310 3560);
DISPLAY INVISIBLE (2310 3560);
FORCEPROP 1 LASTPIN (2300 3550) BN 4
J 2
(2350 3560);
DISPLAY 0.617021 (2350 3560);
PAINT PINK (2350 3560);
FORCEPROP 2 LAST CDS_LIB mstr_standard
J 0
(2350 3550);
DISPLAY 0.787234 (2350 3550);
PAINT MONO (2350 3550);
DISPLAY INVISIBLE (2350 3550);
FORCEPROP 1 LAST BODY_TYPE PLUMBING
J 2
(2350 3500);
DISPLAY 1.234043 (2350 3500);
PAINT GREEN (2350 3500);
DISPLAY INVISIBLE (2350 3500);
FORCEPROP 1 LAST HDL_TAP TRUE
J 2
(2025 3425);
DISPLAY 1.234043 (2025 3425);
PAINT GREEN (2025 3425);
DISPLAY INVISIBLE (2025 3425);
FORCEPROP 1 LAST PATH I153
J 2
(2352 3550);
DISPLAY 0.872340 (2352 3550);
PAINT GREEN (2352 3550);
DISPLAY INVISIBLE (2352 3550);
FORCEADD TAP..6
R 2
(2350 3950);
FORCEPROP 3 LASTPIN (2300 3950) SIG_NAME M_A_DQS_DP<8>
J 0
(2310 3960);
DISPLAY 0.659574 (2310 3960);
PAINT MONO (2310 3960);
DISPLAY INVISIBLE (2310 3960);
FORCEPROP 1 LASTPIN (2300 3950) BN 8
J 2
(2350 3960);
DISPLAY 0.617021 (2350 3960);
PAINT PINK (2350 3960);
FORCEPROP 2 LAST CDS_LIB mstr_standard
J 0
(2350 3950);
DISPLAY 0.787234 (2350 3950);
PAINT MONO (2350 3950);
DISPLAY INVISIBLE (2350 3950);
FORCEPROP 1 LAST BODY_TYPE PLUMBING
J 2
(2350 3900);
DISPLAY 1.234043 (2350 3900);
PAINT GREEN (2350 3900);
DISPLAY INVISIBLE (2350 3900);
FORCEPROP 1 LAST HDL_TAP TRUE
J 2
(2025 3825);
DISPLAY 1.234043 (2025 3825);
PAINT GREEN (2025 3825);
DISPLAY INVISIBLE (2025 3825);
FORCEPROP 1 LAST PATH I154
J 2
(2352 3950);
DISPLAY 0.872340 (2352 3950);
PAINT GREEN (2352 3950);
DISPLAY INVISIBLE (2352 3950);
FORCEADD TAP..6
R 2
(2350 3850);
FORCEPROP 3 LASTPIN (2300 3850) SIG_NAME M_A_DQS_DP<7>
J 0
(2310 3860);
DISPLAY 0.659574 (2310 3860);
PAINT MONO (2310 3860);
DISPLAY INVISIBLE (2310 3860);
FORCEPROP 1 LASTPIN (2300 3850) BN 7
J 2
(2350 3860);
DISPLAY 0.617021 (2350 3860);
PAINT PINK (2350 3860);
FORCEPROP 2 LAST CDS_LIB mstr_standard
J 0
(2350 3850);
DISPLAY 0.787234 (2350 3850);
PAINT MONO (2350 3850);
DISPLAY INVISIBLE (2350 3850);
FORCEPROP 1 LAST BODY_TYPE PLUMBING
J 2
(2350 3800);
DISPLAY 1.234043 (2350 3800);
PAINT GREEN (2350 3800);
DISPLAY INVISIBLE (2350 3800);
FORCEPROP 1 LAST HDL_TAP TRUE
J 2
(2025 3725);
DISPLAY 1.234043 (2025 3725);
PAINT GREEN (2025 3725);
DISPLAY INVISIBLE (2025 3725);
FORCEPROP 1 LAST PATH I155
J 2
(2352 3850);
DISPLAY 0.872340 (2352 3850);
PAINT GREEN (2352 3850);
DISPLAY INVISIBLE (2352 3850);
FORCEADD TAP..6
R 2
(2550 3600);
FORCEPROP 3 LASTPIN (2500 3600) SIG_NAME M_A_DQS_DN<5>
J 0
(2510 3610);
DISPLAY 0.659574 (2510 3610);
PAINT MONO (2510 3610);
DISPLAY INVISIBLE (2510 3610);
FORCEPROP 1 LASTPIN (2500 3600) BN 5
J 2
(2550 3610);
DISPLAY 0.617021 (2550 3610);
PAINT PINK (2550 3610);
FORCEPROP 2 LAST CDS_LIB mstr_standard
J 0
(2550 3600);
DISPLAY 0.787234 (2550 3600);
PAINT MONO (2550 3600);
DISPLAY INVISIBLE (2550 3600);
FORCEPROP 1 LAST BODY_TYPE PLUMBING
J 2
(2550 3550);
DISPLAY 1.234043 (2550 3550);
PAINT GREEN (2550 3550);
DISPLAY INVISIBLE (2550 3550);
FORCEPROP 1 LAST HDL_TAP TRUE
J 2
(2225 3475);
DISPLAY 1.234043 (2225 3475);
PAINT GREEN (2225 3475);
DISPLAY INVISIBLE (2225 3475);
FORCEPROP 1 LAST PATH I156
J 2
(2552 3600);
DISPLAY 0.872340 (2552 3600);
PAINT GREEN (2552 3600);
DISPLAY INVISIBLE (2552 3600);
FORCEADD TAP..6
R 2
(2550 3700);
FORCEPROP 3 LASTPIN (2500 3700) SIG_NAME M_A_DQS_DN<6>
J 0
(2510 3710);
DISPLAY 0.659574 (2510 3710);
PAINT MONO (2510 3710);
DISPLAY INVISIBLE (2510 3710);
FORCEPROP 1 LASTPIN (2500 3700) BN 6
J 2
(2550 3710);
DISPLAY 0.617021 (2550 3710);
PAINT PINK (2550 3710);
FORCEPROP 2 LAST CDS_LIB mstr_standard
J 0
(2550 3700);
DISPLAY 0.787234 (2550 3700);
PAINT MONO (2550 3700);
DISPLAY INVISIBLE (2550 3700);
FORCEPROP 1 LAST BODY_TYPE PLUMBING
J 2
(2550 3650);
DISPLAY 1.234043 (2550 3650);
PAINT GREEN (2550 3650);
DISPLAY INVISIBLE (2550 3650);
FORCEPROP 1 LAST HDL_TAP TRUE
J 2
(2225 3575);
DISPLAY 1.234043 (2225 3575);
PAINT GREEN (2225 3575);
DISPLAY INVISIBLE (2225 3575);
FORCEPROP 1 LAST PATH I157
J 2
(2552 3700);
DISPLAY 0.872340 (2552 3700);
PAINT GREEN (2552 3700);
DISPLAY INVISIBLE (2552 3700);
FORCEADD TAP..6
R 2
(2550 3800);
FORCEPROP 3 LASTPIN (2500 3800) SIG_NAME M_A_DQS_DN<7>
J 0
(2510 3810);
DISPLAY 0.659574 (2510 3810);
PAINT MONO (2510 3810);
DISPLAY INVISIBLE (2510 3810);
FORCEPROP 1 LASTPIN (2500 3800) BN 7
J 2
(2550 3810);
DISPLAY 0.617021 (2550 3810);
PAINT PINK (2550 3810);
FORCEPROP 2 LAST CDS_LIB mstr_standard
J 0
(2550 3800);
DISPLAY 0.787234 (2550 3800);
PAINT MONO (2550 3800);
DISPLAY INVISIBLE (2550 3800);
FORCEPROP 1 LAST BODY_TYPE PLUMBING
J 2
(2550 3750);
DISPLAY 1.234043 (2550 3750);
PAINT GREEN (2550 3750);
DISPLAY INVISIBLE (2550 3750);
FORCEPROP 1 LAST HDL_TAP TRUE
J 2
(2225 3675);
DISPLAY 1.234043 (2225 3675);
PAINT GREEN (2225 3675);
DISPLAY INVISIBLE (2225 3675);
FORCEPROP 1 LAST PATH I158
J 2
(2552 3800);
DISPLAY 0.872340 (2552 3800);
PAINT GREEN (2552 3800);
DISPLAY INVISIBLE (2552 3800);
FORCEADD TAP..6
R 2
(2550 3900);
FORCEPROP 3 LASTPIN (2500 3900) SIG_NAME M_A_DQS_DN<8>
J 0
(2510 3910);
DISPLAY 0.659574 (2510 3910);
PAINT MONO (2510 3910);
DISPLAY INVISIBLE (2510 3910);
FORCEPROP 1 LASTPIN (2500 3900) BN 8
J 2
(2550 3910);
DISPLAY 0.617021 (2550 3910);
PAINT PINK (2550 3910);
FORCEPROP 2 LAST CDS_LIB mstr_standard
J 0
(2550 3900);
DISPLAY 0.787234 (2550 3900);
PAINT MONO (2550 3900);
DISPLAY INVISIBLE (2550 3900);
FORCEPROP 1 LAST BODY_TYPE PLUMBING
J 2
(2550 3850);
DISPLAY 1.234043 (2550 3850);
PAINT GREEN (2550 3850);
DISPLAY INVISIBLE (2550 3850);
FORCEPROP 1 LAST HDL_TAP TRUE
J 2
(2225 3775);
DISPLAY 1.234043 (2225 3775);
PAINT GREEN (2225 3775);
DISPLAY INVISIBLE (2225 3775);
FORCEPROP 1 LAST PATH I159
J 2
(2552 3900);
DISPLAY 0.872340 (2552 3900);
PAINT GREEN (2552 3900);
DISPLAY INVISIBLE (2552 3900);
FORCEADD OFFPAGE..1
(-2100 2300);
FORCEPROP 2 LAST $XR0 23 
J 0
(-2381 2300);
DISPLAY 0.638298 (-2381 2300);
PAINT MONO (-2381 2300);
FORCEPROP 2 LAST $XR1 43 
J 0
(-2471 2300);
DISPLAY 0.638298 (-2471 2300);
PAINT MONO (-2471 2300);
FORCEPROP 2 LAST CDS_LIB mstr_standard
J 0
(-2100 2300);
DISPLAY 0.787234 (-2100 2300);
PAINT MONO (-2100 2300);
DISPLAY INVISIBLE (-2100 2300);
FORCEPROP 1 LAST OFFPAGE TRUE
J 0
(-1775 2175);
DISPLAY 0.936170 (-1775 2175);
PAINT GREEN (-1775 2175);
DISPLAY INVISIBLE (-1775 2175);
FORCEPROP 1 LAST COMMENT_BODY TRUE
J 0
(-1975 2200);
DISPLAY 0.936170 (-1975 2200);
PAINT GREEN (-1975 2200);
DISPLAY INVISIBLE (-1975 2200);
FORCEPROP 2 LAST PATH I16
J 0
(-2375 2350);
DISPLAY 1.021277 (-2375 2350);
PAINT ORANGE (-2375 2350);
DISPLAY INVISIBLE (-2375 2350);
FORCEADD TAP..6
R 2
(2550 4000);
FORCEPROP 3 LASTPIN (2500 4000) SIG_NAME M_A_DQS_DN<9>
J 0
(2510 4010);
DISPLAY 0.659574 (2510 4010);
PAINT MONO (2510 4010);
DISPLAY INVISIBLE (2510 4010);
FORCEPROP 1 LASTPIN (2500 4000) BN 9
J 2
(2550 4010);
DISPLAY 0.617021 (2550 4010);
PAINT PINK (2550 4010);
FORCEPROP 2 LAST CDS_LIB mstr_standard
J 0
(2550 4000);
DISPLAY 0.787234 (2550 4000);
PAINT MONO (2550 4000);
DISPLAY INVISIBLE (2550 4000);
FORCEPROP 1 LAST BODY_TYPE PLUMBING
J 2
(2550 3950);
DISPLAY 1.234043 (2550 3950);
PAINT GREEN (2550 3950);
DISPLAY INVISIBLE (2550 3950);
FORCEPROP 1 LAST HDL_TAP TRUE
J 2
(2225 3875);
DISPLAY 1.234043 (2225 3875);
PAINT GREEN (2225 3875);
DISPLAY INVISIBLE (2225 3875);
FORCEPROP 1 LAST PATH I160
J 2
(2552 4000);
DISPLAY 0.872340 (2552 4000);
PAINT GREEN (2552 4000);
DISPLAY INVISIBLE (2552 4000);
FORCEADD GND..1
R 2
(4150 1100);
FORCEPROP 3 LASTPIN (4150 1150) SIG_NAME GND\g
J 0
(4160 1160);
DISPLAY 0.659574 (4160 1160);
PAINT MONO (4160 1160);
DISPLAY INVISIBLE (4160 1160);
FORCEPROP 1 LAST VOLTAGE 0
J 0
(4150 1100);
PAINT SKYBLUE (4150 1100);
DISPLAY INVISIBLE (4150 1100);
FORCEPROP 1 LAST SIZE 1B
J 2
(4075 1050);
DISPLAY 1.170213 (4075 1050);
PAINT GREEN (4075 1050);
DISPLAY INVISIBLE (4075 1050);
FORCEPROP 2 LAST BOM_COST MEM
J 0
(4150 1105);
PAINT ORANGE (4150 1105);
DISPLAY INVISIBLE (4150 1105);
FORCEPROP 2 LAST CDS_LIB mstr_symbols
J 0
(4150 1100);
DISPLAY 0.787234 (4150 1100);
PAINT MONO (4150 1100);
DISPLAY INVISIBLE (4150 1100);
FORCEPROP 1 LAST BODY_TYPE PLUMBING
J 2
(4195 1057);
DISPLAY 0.340426 (4195 1057);
PAINT GREEN (4195 1057);
DISPLAY INVISIBLE (4195 1057);
FORCEPROP 1 LAST PATH I162
J 2
(4075 1100);
DISPLAY 0.872340 (4075 1100);
PAINT AQUA (4075 1100);
DISPLAY INVISIBLE (4075 1100);
FORCEPROP 2 LAST ROOM DDR4_CH_A
J 0
(4150 1105);
PAINT ORANGE (4150 1105);
DISPLAY INVISIBLE (4150 1105);
FORCEPROP 1 LAST HDL_POWER GND
J 2
(4150 1250);
DISPLAY 0.553191 (4150 1250);
PAINT GREEN (4150 1250);
DISPLAY INVISIBLE (4150 1250);
FORCEADD TAP..6
R 2
(2350 4150);
FORCEPROP 3 LASTPIN (2300 4150) SIG_NAME M_A_DQS_DP<10>
J 0
(2310 4160);
DISPLAY 0.659574 (2310 4160);
PAINT MONO (2310 4160);
DISPLAY INVISIBLE (2310 4160);
FORCEPROP 1 LASTPIN (2300 4150) BN 10
J 2
(2350 4160);
DISPLAY 0.617021 (2350 4160);
PAINT PINK (2350 4160);
FORCEPROP 2 LAST CDS_LIB mstr_standard
J 0
(2350 4150);
DISPLAY 0.787234 (2350 4150);
PAINT MONO (2350 4150);
DISPLAY INVISIBLE (2350 4150);
FORCEPROP 1 LAST BODY_TYPE PLUMBING
J 2
(2350 4100);
DISPLAY 1.234043 (2350 4100);
PAINT GREEN (2350 4100);
DISPLAY INVISIBLE (2350 4100);
FORCEPROP 1 LAST HDL_TAP TRUE
J 2
(2025 4025);
DISPLAY 1.234043 (2025 4025);
PAINT GREEN (2025 4025);
DISPLAY INVISIBLE (2025 4025);
FORCEPROP 1 LAST PATH I163
J 2
(2352 4150);
DISPLAY 0.872340 (2352 4150);
PAINT GREEN (2352 4150);
DISPLAY INVISIBLE (2352 4150);
FORCEADD TAP..6
R 2
(2350 4250);
FORCEPROP 3 LASTPIN (2300 4250) SIG_NAME M_A_DQS_DP<11>
J 0
(2310 4260);
DISPLAY 0.659574 (2310 4260);
PAINT MONO (2310 4260);
DISPLAY INVISIBLE (2310 4260);
FORCEPROP 1 LASTPIN (2300 4250) BN 11
J 2
(2350 4260);
DISPLAY 0.617021 (2350 4260);
PAINT PINK (2350 4260);
FORCEPROP 2 LAST CDS_LIB mstr_standard
J 0
(2350 4250);
DISPLAY 0.787234 (2350 4250);
PAINT MONO (2350 4250);
DISPLAY INVISIBLE (2350 4250);
FORCEPROP 1 LAST BODY_TYPE PLUMBING
J 2
(2350 4200);
DISPLAY 1.234043 (2350 4200);
PAINT GREEN (2350 4200);
DISPLAY INVISIBLE (2350 4200);
FORCEPROP 1 LAST HDL_TAP TRUE
J 2
(2025 4125);
DISPLAY 1.234043 (2025 4125);
PAINT GREEN (2025 4125);
DISPLAY INVISIBLE (2025 4125);
FORCEPROP 1 LAST PATH I164
J 2
(2352 4250);
DISPLAY 0.872340 (2352 4250);
PAINT GREEN (2352 4250);
DISPLAY INVISIBLE (2352 4250);
FORCEADD TAP..6
R 2
(2350 4050);
FORCEPROP 3 LASTPIN (2300 4050) SIG_NAME M_A_DQS_DP<9>
J 0
(2310 4060);
DISPLAY 0.659574 (2310 4060);
PAINT MONO (2310 4060);
DISPLAY INVISIBLE (2310 4060);
FORCEPROP 1 LASTPIN (2300 4050) BN 9
J 2
(2350 4060);
DISPLAY 0.617021 (2350 4060);
PAINT PINK (2350 4060);
FORCEPROP 2 LAST CDS_LIB mstr_standard
J 0
(2350 4050);
DISPLAY 0.787234 (2350 4050);
PAINT MONO (2350 4050);
DISPLAY INVISIBLE (2350 4050);
FORCEPROP 1 LAST BODY_TYPE PLUMBING
J 2
(2350 4000);
DISPLAY 1.234043 (2350 4000);
PAINT GREEN (2350 4000);
DISPLAY INVISIBLE (2350 4000);
FORCEPROP 1 LAST HDL_TAP TRUE
J 2
(2025 3925);
DISPLAY 1.234043 (2025 3925);
PAINT GREEN (2025 3925);
DISPLAY INVISIBLE (2025 3925);
FORCEPROP 1 LAST PATH I165
J 2
(2352 4050);
DISPLAY 0.872340 (2352 4050);
PAINT GREEN (2352 4050);
DISPLAY INVISIBLE (2352 4050);
FORCEADD TAP..6
R 2
(2350 4350);
FORCEPROP 3 LASTPIN (2300 4350) SIG_NAME M_A_DQS_DP<12>
J 0
(2310 4360);
DISPLAY 0.659574 (2310 4360);
PAINT MONO (2310 4360);
DISPLAY INVISIBLE (2310 4360);
FORCEPROP 1 LASTPIN (2300 4350) BN 12
J 2
(2350 4360);
DISPLAY 0.617021 (2350 4360);
PAINT PINK (2350 4360);
FORCEPROP 2 LAST CDS_LIB mstr_standard
J 0
(2350 4350);
DISPLAY 0.787234 (2350 4350);
PAINT MONO (2350 4350);
DISPLAY INVISIBLE (2350 4350);
FORCEPROP 1 LAST BODY_TYPE PLUMBING
J 2
(2350 4300);
DISPLAY 1.234043 (2350 4300);
PAINT GREEN (2350 4300);
DISPLAY INVISIBLE (2350 4300);
FORCEPROP 1 LAST HDL_TAP TRUE
J 2
(2025 4225);
DISPLAY 1.234043 (2025 4225);
PAINT GREEN (2025 4225);
DISPLAY INVISIBLE (2025 4225);
FORCEPROP 1 LAST PATH I166
J 2
(2352 4350);
DISPLAY 0.872340 (2352 4350);
PAINT GREEN (2352 4350);
DISPLAY INVISIBLE (2352 4350);
FORCEADD TAP..6
R 2
(2350 4550);
FORCEPROP 3 LASTPIN (2300 4550) SIG_NAME M_A_DQS_DP<14>
J 0
(2310 4560);
DISPLAY 0.659574 (2310 4560);
PAINT MONO (2310 4560);
DISPLAY INVISIBLE (2310 4560);
FORCEPROP 1 LASTPIN (2300 4550) BN 14
J 2
(2350 4560);
DISPLAY 0.617021 (2350 4560);
PAINT PINK (2350 4560);
FORCEPROP 2 LAST CDS_LIB mstr_standard
J 0
(2350 4550);
DISPLAY 0.787234 (2350 4550);
PAINT MONO (2350 4550);
DISPLAY INVISIBLE (2350 4550);
FORCEPROP 1 LAST BODY_TYPE PLUMBING
J 2
(2350 4500);
DISPLAY 1.234043 (2350 4500);
PAINT GREEN (2350 4500);
DISPLAY INVISIBLE (2350 4500);
FORCEPROP 1 LAST HDL_TAP TRUE
J 2
(2025 4425);
DISPLAY 1.234043 (2025 4425);
PAINT GREEN (2025 4425);
DISPLAY INVISIBLE (2025 4425);
FORCEPROP 1 LAST PATH I167
J 2
(2352 4550);
DISPLAY 0.872340 (2352 4550);
PAINT GREEN (2352 4550);
DISPLAY INVISIBLE (2352 4550);
FORCEADD TAP..6
R 2
(2350 4450);
FORCEPROP 3 LASTPIN (2300 4450) SIG_NAME M_A_DQS_DP<13>
J 0
(2310 4460);
DISPLAY 0.659574 (2310 4460);
PAINT MONO (2310 4460);
DISPLAY INVISIBLE (2310 4460);
FORCEPROP 1 LASTPIN (2300 4450) BN 13
J 2
(2350 4460);
DISPLAY 0.617021 (2350 4460);
PAINT PINK (2350 4460);
FORCEPROP 2 LAST CDS_LIB mstr_standard
J 0
(2350 4450);
DISPLAY 0.787234 (2350 4450);
PAINT MONO (2350 4450);
DISPLAY INVISIBLE (2350 4450);
FORCEPROP 1 LAST BODY_TYPE PLUMBING
J 2
(2350 4400);
DISPLAY 1.234043 (2350 4400);
PAINT GREEN (2350 4400);
DISPLAY INVISIBLE (2350 4400);
FORCEPROP 1 LAST HDL_TAP TRUE
J 2
(2025 4325);
DISPLAY 1.234043 (2025 4325);
PAINT GREEN (2025 4325);
DISPLAY INVISIBLE (2025 4325);
FORCEPROP 1 LAST PATH I168
J 2
(2352 4450);
DISPLAY 0.872340 (2352 4450);
PAINT GREEN (2352 4450);
DISPLAY INVISIBLE (2352 4450);
FORCEADD TAP..6
R 2
(2550 4100);
FORCEPROP 3 LASTPIN (2500 4100) SIG_NAME M_A_DQS_DN<10>
J 0
(2510 4110);
DISPLAY 0.659574 (2510 4110);
PAINT MONO (2510 4110);
DISPLAY INVISIBLE (2510 4110);
FORCEPROP 1 LASTPIN (2500 4100) BN 10
J 2
(2550 4110);
DISPLAY 0.617021 (2550 4110);
PAINT PINK (2550 4110);
FORCEPROP 2 LAST CDS_LIB mstr_standard
J 0
(2550 4100);
DISPLAY 0.787234 (2550 4100);
PAINT MONO (2550 4100);
DISPLAY INVISIBLE (2550 4100);
FORCEPROP 1 LAST BODY_TYPE PLUMBING
J 2
(2550 4050);
DISPLAY 1.234043 (2550 4050);
PAINT GREEN (2550 4050);
DISPLAY INVISIBLE (2550 4050);
FORCEPROP 1 LAST HDL_TAP TRUE
J 2
(2225 3975);
DISPLAY 1.234043 (2225 3975);
PAINT GREEN (2225 3975);
DISPLAY INVISIBLE (2225 3975);
FORCEPROP 1 LAST PATH I169
J 2
(2552 4100);
DISPLAY 0.872340 (2552 4100);
PAINT GREEN (2552 4100);
DISPLAY INVISIBLE (2552 4100);
FORCEADD OFFPAGE..1
(-2100 2500);
FORCEPROP 2 LAST $XR0 23 
J 0
(-2321 2500);
DISPLAY 0.638298 (-2321 2500);
PAINT MONO (-2321 2500);
FORCEPROP 2 LAST $XR1 43 
J 0
(-2411 2500);
DISPLAY 0.638298 (-2411 2500);
PAINT MONO (-2411 2500);
FORCEPROP 2 LAST CDS_LIB mstr_standard
J 0
(-2100 2500);
DISPLAY 0.787234 (-2100 2500);
PAINT MONO (-2100 2500);
DISPLAY INVISIBLE (-2100 2500);
FORCEPROP 1 LAST OFFPAGE TRUE
J 0
(-1775 2375);
DISPLAY 0.936170 (-1775 2375);
PAINT GREEN (-1775 2375);
DISPLAY INVISIBLE (-1775 2375);
FORCEPROP 1 LAST COMMENT_BODY TRUE
J 0
(-1975 2400);
DISPLAY 0.936170 (-1975 2400);
PAINT GREEN (-1975 2400);
DISPLAY INVISIBLE (-1975 2400);
FORCEPROP 2 LAST PATH I17
J 0
(-2300 2550);
DISPLAY 1.021277 (-2300 2550);
PAINT ORANGE (-2300 2550);
DISPLAY INVISIBLE (-2300 2550);
FORCEADD TAP..6
R 2
(2550 4300);
FORCEPROP 3 LASTPIN (2500 4300) SIG_NAME M_A_DQS_DN<12>
J 0
(2510 4310);
DISPLAY 0.659574 (2510 4310);
PAINT MONO (2510 4310);
DISPLAY INVISIBLE (2510 4310);
FORCEPROP 1 LASTPIN (2500 4300) BN 12
J 2
(2550 4310);
DISPLAY 0.617021 (2550 4310);
PAINT PINK (2550 4310);
FORCEPROP 2 LAST CDS_LIB mstr_standard
J 0
(2550 4300);
DISPLAY 0.787234 (2550 4300);
PAINT MONO (2550 4300);
DISPLAY INVISIBLE (2550 4300);
FORCEPROP 1 LAST BODY_TYPE PLUMBING
J 2
(2550 4250);
DISPLAY 1.234043 (2550 4250);
PAINT GREEN (2550 4250);
DISPLAY INVISIBLE (2550 4250);
FORCEPROP 1 LAST HDL_TAP TRUE
J 2
(2225 4175);
DISPLAY 1.234043 (2225 4175);
PAINT GREEN (2225 4175);
DISPLAY INVISIBLE (2225 4175);
FORCEPROP 1 LAST PATH I170
J 2
(2552 4300);
DISPLAY 0.872340 (2552 4300);
PAINT GREEN (2552 4300);
DISPLAY INVISIBLE (2552 4300);
FORCEADD TAP..6
R 2
(2550 4200);
FORCEPROP 3 LASTPIN (2500 4200) SIG_NAME M_A_DQS_DN<11>
J 0
(2510 4210);
DISPLAY 0.659574 (2510 4210);
PAINT MONO (2510 4210);
DISPLAY INVISIBLE (2510 4210);
FORCEPROP 1 LASTPIN (2500 4200) BN 11
J 2
(2550 4210);
DISPLAY 0.617021 (2550 4210);
PAINT PINK (2550 4210);
FORCEPROP 2 LAST CDS_LIB mstr_standard
J 0
(2550 4200);
DISPLAY 0.787234 (2550 4200);
PAINT MONO (2550 4200);
DISPLAY INVISIBLE (2550 4200);
FORCEPROP 1 LAST BODY_TYPE PLUMBING
J 2
(2550 4150);
DISPLAY 1.234043 (2550 4150);
PAINT GREEN (2550 4150);
DISPLAY INVISIBLE (2550 4150);
FORCEPROP 1 LAST HDL_TAP TRUE
J 2
(2225 4075);
DISPLAY 1.234043 (2225 4075);
PAINT GREEN (2225 4075);
DISPLAY INVISIBLE (2225 4075);
FORCEPROP 1 LAST PATH I171
J 2
(2552 4200);
DISPLAY 0.872340 (2552 4200);
PAINT GREEN (2552 4200);
DISPLAY INVISIBLE (2552 4200);
FORCEADD TAP..6
R 2
(2550 4400);
FORCEPROP 3 LASTPIN (2500 4400) SIG_NAME M_A_DQS_DN<13>
J 0
(2510 4410);
DISPLAY 0.659574 (2510 4410);
PAINT MONO (2510 4410);
DISPLAY INVISIBLE (2510 4410);
FORCEPROP 1 LASTPIN (2500 4400) BN 13
J 2
(2550 4410);
DISPLAY 0.617021 (2550 4410);
PAINT PINK (2550 4410);
FORCEPROP 2 LAST CDS_LIB mstr_standard
J 0
(2550 4400);
DISPLAY 0.787234 (2550 4400);
PAINT MONO (2550 4400);
DISPLAY INVISIBLE (2550 4400);
FORCEPROP 1 LAST BODY_TYPE PLUMBING
J 2
(2550 4350);
DISPLAY 1.234043 (2550 4350);
PAINT GREEN (2550 4350);
DISPLAY INVISIBLE (2550 4350);
FORCEPROP 1 LAST HDL_TAP TRUE
J 2
(2225 4275);
DISPLAY 1.234043 (2225 4275);
PAINT GREEN (2225 4275);
DISPLAY INVISIBLE (2225 4275);
FORCEPROP 1 LAST PATH I172
J 2
(2552 4400);
DISPLAY 0.872340 (2552 4400);
PAINT GREEN (2552 4400);
DISPLAY INVISIBLE (2552 4400);
FORCEADD TAP..6
R 2
(2550 4500);
FORCEPROP 3 LASTPIN (2500 4500) SIG_NAME M_A_DQS_DN<14>
J 0
(2510 4510);
DISPLAY 0.659574 (2510 4510);
PAINT MONO (2510 4510);
DISPLAY INVISIBLE (2510 4510);
FORCEPROP 1 LASTPIN (2500 4500) BN 14
J 2
(2550 4510);
DISPLAY 0.617021 (2550 4510);
PAINT PINK (2550 4510);
FORCEPROP 2 LAST CDS_LIB mstr_standard
J 0
(2550 4500);
DISPLAY 0.787234 (2550 4500);
PAINT MONO (2550 4500);
DISPLAY INVISIBLE (2550 4500);
FORCEPROP 1 LAST BODY_TYPE PLUMBING
J 2
(2550 4450);
DISPLAY 1.234043 (2550 4450);
PAINT GREEN (2550 4450);
DISPLAY INVISIBLE (2550 4450);
FORCEPROP 1 LAST HDL_TAP TRUE
J 2
(2225 4375);
DISPLAY 1.234043 (2225 4375);
PAINT GREEN (2225 4375);
DISPLAY INVISIBLE (2225 4375);
FORCEPROP 1 LAST PATH I173
J 2
(2552 4500);
DISPLAY 0.872340 (2552 4500);
PAINT GREEN (2552 4500);
DISPLAY INVISIBLE (2552 4500);
FORCEADD TAP..6
R 2
(2350 4650);
FORCEPROP 3 LASTPIN (2300 4650) SIG_NAME M_A_DQS_DP<15>
J 0
(2310 4660);
DISPLAY 0.659574 (2310 4660);
PAINT MONO (2310 4660);
DISPLAY INVISIBLE (2310 4660);
FORCEPROP 1 LASTPIN (2300 4650) BN 15
J 2
(2350 4660);
DISPLAY 0.617021 (2350 4660);
PAINT PINK (2350 4660);
FORCEPROP 2 LAST CDS_LIB mstr_standard
J 0
(2350 4650);
DISPLAY 0.787234 (2350 4650);
PAINT MONO (2350 4650);
DISPLAY INVISIBLE (2350 4650);
FORCEPROP 1 LAST BODY_TYPE PLUMBING
J 2
(2350 4600);
DISPLAY 1.234043 (2350 4600);
PAINT GREEN (2350 4600);
DISPLAY INVISIBLE (2350 4600);
FORCEPROP 1 LAST HDL_TAP TRUE
J 2
(2025 4525);
DISPLAY 1.234043 (2025 4525);
PAINT GREEN (2025 4525);
DISPLAY INVISIBLE (2025 4525);
FORCEPROP 1 LAST PATH I174
J 2
(2352 4650);
DISPLAY 0.872340 (2352 4650);
PAINT GREEN (2352 4650);
DISPLAY INVISIBLE (2352 4650);
FORCEADD TAP..6
R 2
(2350 4750);
FORCEPROP 3 LASTPIN (2300 4750) SIG_NAME M_A_DQS_DP<16>
J 0
(2310 4760);
DISPLAY 0.659574 (2310 4760);
PAINT MONO (2310 4760);
DISPLAY INVISIBLE (2310 4760);
FORCEPROP 1 LASTPIN (2300 4750) BN 16
J 2
(2350 4760);
DISPLAY 0.617021 (2350 4760);
PAINT PINK (2350 4760);
FORCEPROP 2 LAST CDS_LIB mstr_standard
J 0
(2350 4750);
DISPLAY 0.787234 (2350 4750);
PAINT MONO (2350 4750);
DISPLAY INVISIBLE (2350 4750);
FORCEPROP 1 LAST BODY_TYPE PLUMBING
J 2
(2350 4700);
DISPLAY 1.234043 (2350 4700);
PAINT GREEN (2350 4700);
DISPLAY INVISIBLE (2350 4700);
FORCEPROP 1 LAST HDL_TAP TRUE
J 2
(2025 4625);
DISPLAY 1.234043 (2025 4625);
PAINT GREEN (2025 4625);
DISPLAY INVISIBLE (2025 4625);
FORCEPROP 1 LAST PATH I175
J 2
(2352 4750);
DISPLAY 0.872340 (2352 4750);
PAINT GREEN (2352 4750);
DISPLAY INVISIBLE (2352 4750);
FORCEADD TAP..6
R 2
(2350 4850);
FORCEPROP 3 LASTPIN (2300 4850) SIG_NAME M_A_DQS_DP<17>
J 0
(2310 4860);
DISPLAY 0.659574 (2310 4860);
PAINT MONO (2310 4860);
DISPLAY INVISIBLE (2310 4860);
FORCEPROP 1 LASTPIN (2300 4850) BN 17
J 2
(2350 4860);
DISPLAY 0.617021 (2350 4860);
PAINT PINK (2350 4860);
FORCEPROP 2 LAST CDS_LIB mstr_standard
J 2
(2350 4850);
DISPLAY 0.787234 (2350 4850);
PAINT MONO (2350 4850);
DISPLAY INVISIBLE (2350 4850);
FORCEPROP 1 LAST BODY_TYPE PLUMBING
J 2
(2350 4800);
DISPLAY 1.234043 (2350 4800);
PAINT GREEN (2350 4800);
DISPLAY INVISIBLE (2350 4800);
FORCEPROP 1 LAST HDL_TAP TRUE
J 2
(2025 4725);
DISPLAY 1.234043 (2025 4725);
PAINT GREEN (2025 4725);
DISPLAY INVISIBLE (2025 4725);
FORCEPROP 1 LAST PATH I176
J 2
(2352 4850);
DISPLAY 0.872340 (2352 4850);
PAINT GREEN (2352 4850);
DISPLAY INVISIBLE (2352 4850);
FORCEADD TAP..6
R 2
(2550 4600);
FORCEPROP 3 LASTPIN (2500 4600) SIG_NAME M_A_DQS_DN<15>
J 0
(2510 4610);
DISPLAY 0.659574 (2510 4610);
PAINT MONO (2510 4610);
DISPLAY INVISIBLE (2510 4610);
FORCEPROP 1 LASTPIN (2500 4600) BN 15
J 2
(2550 4610);
DISPLAY 0.617021 (2550 4610);
PAINT PINK (2550 4610);
FORCEPROP 2 LAST CDS_LIB mstr_standard
J 0
(2550 4600);
DISPLAY 0.787234 (2550 4600);
PAINT MONO (2550 4600);
DISPLAY INVISIBLE (2550 4600);
FORCEPROP 1 LAST BODY_TYPE PLUMBING
J 2
(2550 4550);
DISPLAY 1.234043 (2550 4550);
PAINT GREEN (2550 4550);
DISPLAY INVISIBLE (2550 4550);
FORCEPROP 1 LAST HDL_TAP TRUE
J 2
(2225 4475);
DISPLAY 1.234043 (2225 4475);
PAINT GREEN (2225 4475);
DISPLAY INVISIBLE (2225 4475);
FORCEPROP 1 LAST PATH I177
J 2
(2552 4600);
DISPLAY 0.872340 (2552 4600);
PAINT GREEN (2552 4600);
DISPLAY INVISIBLE (2552 4600);
FORCEADD TAP..6
R 2
(2550 4800);
FORCEPROP 3 LASTPIN (2500 4800) SIG_NAME M_A_DQS_DN<17>
J 0
(2510 4810);
DISPLAY 0.659574 (2510 4810);
PAINT MONO (2510 4810);
DISPLAY INVISIBLE (2510 4810);
FORCEPROP 1 LASTPIN (2500 4800) BN 17
J 2
(2550 4810);
DISPLAY 0.617021 (2550 4810);
PAINT PINK (2550 4810);
FORCEPROP 2 LAST CDS_LIB mstr_standard
J 2
(2550 4800);
DISPLAY 0.787234 (2550 4800);
PAINT MONO (2550 4800);
DISPLAY INVISIBLE (2550 4800);
FORCEPROP 1 LAST BODY_TYPE PLUMBING
J 2
(2550 4750);
DISPLAY 1.234043 (2550 4750);
PAINT GREEN (2550 4750);
DISPLAY INVISIBLE (2550 4750);
FORCEPROP 1 LAST HDL_TAP TRUE
J 2
(2225 4675);
DISPLAY 1.234043 (2225 4675);
PAINT GREEN (2225 4675);
DISPLAY INVISIBLE (2225 4675);
FORCEPROP 1 LAST PATH I178
J 2
(2552 4800);
DISPLAY 0.872340 (2552 4800);
PAINT GREEN (2552 4800);
DISPLAY INVISIBLE (2552 4800);
FORCEADD TAP..6
R 2
(2550 4700);
FORCEPROP 3 LASTPIN (2500 4700) SIG_NAME M_A_DQS_DN<16>
J 0
(2510 4710);
DISPLAY 0.659574 (2510 4710);
PAINT MONO (2510 4710);
DISPLAY INVISIBLE (2510 4710);
FORCEPROP 1 LASTPIN (2500 4700) BN 16
J 2
(2550 4710);
DISPLAY 0.617021 (2550 4710);
PAINT PINK (2550 4710);
FORCEPROP 2 LAST CDS_LIB mstr_standard
J 0
(2550 4700);
DISPLAY 0.787234 (2550 4700);
PAINT MONO (2550 4700);
DISPLAY INVISIBLE (2550 4700);
FORCEPROP 1 LAST BODY_TYPE PLUMBING
J 2
(2550 4650);
DISPLAY 1.234043 (2550 4650);
PAINT GREEN (2550 4650);
DISPLAY INVISIBLE (2550 4650);
FORCEPROP 1 LAST HDL_TAP TRUE
J 2
(2225 4575);
DISPLAY 1.234043 (2225 4575);
PAINT GREEN (2225 4575);
DISPLAY INVISIBLE (2225 4575);
FORCEPROP 1 LAST PATH I179
J 2
(2552 4700);
DISPLAY 0.872340 (2552 4700);
PAINT GREEN (2552 4700);
DISPLAY INVISIBLE (2552 4700);
FORCEADD OFFPAGE..1
(-2100 2950);
FORCEPROP 2 LAST $XR0 23 
J 0
(-2321 2950);
DISPLAY 0.638298 (-2321 2950);
PAINT MONO (-2321 2950);
FORCEPROP 2 LAST $XR1 43 
J 0
(-2411 2950);
DISPLAY 0.638298 (-2411 2950);
PAINT MONO (-2411 2950);
FORCEPROP 2 LAST CDS_LIB mstr_standard
J 0
(-2100 2950);
DISPLAY 0.787234 (-2100 2950);
PAINT MONO (-2100 2950);
DISPLAY INVISIBLE (-2100 2950);
FORCEPROP 1 LAST OFFPAGE TRUE
J 0
(-1775 2825);
DISPLAY 0.936170 (-1775 2825);
PAINT GREEN (-1775 2825);
DISPLAY INVISIBLE (-1775 2825);
FORCEPROP 1 LAST COMMENT_BODY TRUE
J 0
(-1975 2850);
DISPLAY 0.936170 (-1975 2850);
PAINT GREEN (-1975 2850);
DISPLAY INVISIBLE (-1975 2850);
FORCEPROP 2 LAST PATH I18
J 0
(-2300 3000);
DISPLAY 1.021277 (-2300 3000);
PAINT ORANGE (-2300 3000);
DISPLAY INVISIBLE (-2300 3000);
FORCEADD OFFPAGE..3
(3250 4900);
FORCEPROP 2 LAST $XR0 23 
J 0
(3464 4900);
DISPLAY 0.638298 (3464 4900);
PAINT MONO (3464 4900);
FORCEPROP 2 LAST $XR1 43 
J 0
(3554 4900);
DISPLAY 0.638298 (3554 4900);
PAINT MONO (3554 4900);
FORCEPROP 2 LAST CDS_LIB mstr_standard
J 0
(3250 4900);
DISPLAY 0.787234 (3250 4900);
PAINT MONO (3250 4900);
DISPLAY INVISIBLE (3250 4900);
FORCEPROP 1 LAST OFFPAGE TRUE
J 0
(3575 4775);
DISPLAY 0.936170 (3575 4775);
PAINT GREEN (3575 4775);
DISPLAY INVISIBLE (3575 4775);
FORCEPROP 1 LAST COMMENT_BODY TRUE
J 0
(3200 4800);
DISPLAY 0.936170 (3200 4800);
PAINT GREEN (3200 4800);
DISPLAY INVISIBLE (3200 4800);
FORCEPROP 2 LAST PATH I182
J 0
(3475 4950);
DISPLAY 1.021277 (3475 4950);
PAINT ORANGE (3475 4950);
DISPLAY INVISIBLE (3475 4950);
FORCEADD OFFPAGE..3
(3250 4850);
FORCEPROP 2 LAST $XR0 23 
J 0
(3464 4850);
DISPLAY 0.638298 (3464 4850);
PAINT MONO (3464 4850);
FORCEPROP 2 LAST $XR1 43 
J 0
(3554 4850);
DISPLAY 0.638298 (3554 4850);
PAINT MONO (3554 4850);
FORCEPROP 2 LAST CDS_LIB mstr_standard
J 0
(3250 4850);
DISPLAY 0.787234 (3250 4850);
PAINT MONO (3250 4850);
DISPLAY INVISIBLE (3250 4850);
FORCEPROP 1 LAST OFFPAGE TRUE
J 0
(3575 4725);
DISPLAY 0.936170 (3575 4725);
PAINT GREEN (3575 4725);
DISPLAY INVISIBLE (3575 4725);
FORCEPROP 1 LAST COMMENT_BODY TRUE
J 0
(3200 4750);
DISPLAY 0.936170 (3200 4750);
PAINT GREEN (3200 4750);
DISPLAY INVISIBLE (3200 4750);
FORCEPROP 2 LAST PATH I183
J 0
(3475 4900);
DISPLAY 1.021277 (3475 4900);
PAINT ORANGE (3475 4900);
DISPLAY INVISIBLE (3475 4900);
FORCEADD P12V_NVDIMM_ABC..1
(2300 2725);
FORCEPROP 3 LASTPIN (2300 2675) SIG_NAME P12V_NVDIMM_ABC\g
J 0
(2310 2685);
DISPLAY 0.659574 (2310 2685);
PAINT MONO (2310 2685);
DISPLAY INVISIBLE (2310 2685);
FORCEPROP 1 LAST VOLTAGE 12.0
J 0
(2255 2682);
DISPLAY 0.340426 (2255 2682);
PAINT SKYBLUE (2255 2682);
DISPLAY INVISIBLE (2255 2682);
FORCEPROP 2 LAST CDS_LIB mstr_symbols
J 0
(2300 2725);
PAINT ORANGE (2300 2725);
DISPLAY INVISIBLE (2300 2725);
FORCEPROP 1 LAST BODY_TYPE PLUMBING
J 0
(2255 2682);
DISPLAY 0.340426 (2255 2682);
PAINT GREEN (2255 2682);
DISPLAY INVISIBLE (2255 2682);
FORCEPROP 1 LAST PATH I184
J 0
(2350 2750);
DISPLAY 0.872340 (2350 2750);
PAINT AQUA (2350 2750);
DISPLAY INVISIBLE (2350 2750);
FORCEPROP 1 LAST HDL_POWER P12V_NVDIMM_ABC
J 1
(2300 2750);
DISPLAY 0.872340 (2300 2750);
PAINT GREEN (2300 2750);
DISPLAY INVISIBLE (2300 2750);
FORCEADD OFFPAGE..1
(-2100 2900);
FORCEPROP 2 LAST $XR0 23 
J 0
(-2321 2900);
DISPLAY 0.638298 (-2321 2900);
PAINT MONO (-2321 2900);
FORCEPROP 2 LAST $XR1 43 
J 0
(-2411 2900);
DISPLAY 0.638298 (-2411 2900);
PAINT MONO (-2411 2900);
FORCEPROP 2 LAST CDS_LIB mstr_standard
J 0
(-2100 2900);
DISPLAY 0.787234 (-2100 2900);
PAINT MONO (-2100 2900);
DISPLAY INVISIBLE (-2100 2900);
FORCEPROP 1 LAST OFFPAGE TRUE
J 0
(-1775 2775);
DISPLAY 0.936170 (-1775 2775);
PAINT GREEN (-1775 2775);
DISPLAY INVISIBLE (-1775 2775);
FORCEPROP 1 LAST COMMENT_BODY TRUE
J 0
(-1975 2800);
DISPLAY 0.936170 (-1975 2800);
PAINT GREEN (-1975 2800);
DISPLAY INVISIBLE (-1975 2800);
FORCEPROP 2 LAST PATH I19
J 0
(-2300 2950);
DISPLAY 1.021277 (-2300 2950);
PAINT ORANGE (-2300 2950);
DISPLAY INVISIBLE (-2300 2950);
FORCEADD CAP_A..1
R 2
(-2650 1000);
FORCEPROP 1 LAST LOCATION C6T1
J 2
(-2700 1100);
DISPLAY 0.617021 (-2700 1100);
PAINT AQUA (-2700 1100);
FORCEPROP 1 LAST PART_NUMBER A36096-045
J 2
(-2700 850);
DISPLAY 0.617021 (-2700 850);
PAINT BLUE (-2700 850);
FORCEPROP 1 LAST VALUE 0.01UF
J 2
(-2700 1050);
DISPLAY 0.617021 (-2700 1050);
PAINT SKYBLUE (-2700 1050);
FORCEPROP 1 LAST TOLERANCE 10%
J 2
(-2700 950);
DISPLAY 0.617021 (-2700 950);
PAINT SKYBLUE (-2700 950);
FORCEPROP 1 LAST PACK_TYPE 0402V
J 2
(-2700 800);
DISPLAY 0.617021 (-2700 800);
PAINT SKYBLUE (-2700 800);
FORCEPROP 1 LAST VOLTAGE 25V
J 2
(-2700 1000);
DISPLAY 0.617021 (-2700 1000);
PAINT SKYBLUE (-2700 1000);
FORCEPROP 1 LAST MATERIAL X7R
J 2
(-2700 900);
DISPLAY 0.617021 (-2700 900);
PAINT SKYBLUE (-2700 900);
FORCEPROP 1 LASTPIN (-2650 1100) $PN 1
J 2
(-2660 1080);
DISPLAY 0.617021 (-2660 1080);
PAINT ORANGE (-2660 1080);
FORCEPROP 1 LASTPIN (-2650 900) $PN 2
J 2
(-2660 880);
DISPLAY 0.617021 (-2660 880);
PAINT ORANGE (-2660 880);
FORCEPROP 2 LAST CDS_LOCATION C6T1
J 2
(-2700 1100);
DISPLAY 0.617021 (-2700 1100);
PAINT AQUA (-2700 1100);
DISPLAY INVISIBLE (-2700 1100);
FORCEPROP 2 LAST BOM_COST MEM
J 0
(-2650 1000);
PAINT ORANGE (-2650 1000);
DISPLAY INVISIBLE (-2650 1000);
FORCEPROP 2 LAST CDS_LIB dev_discrete
J 0
(-2650 1000);
PAINT ORANGE (-2650 1000);
DISPLAY INVISIBLE (-2650 1000);
FORCEPROP 2 LAST CDS_SEC 1
J 0
(-2700 1150);
PAINT ORANGE (-2700 1150);
DISPLAY INVISIBLE (-2700 1150);
FORCEPROP 2 LAST SEC_TYPE 0402V
J 0
(-2700 1200);
DISPLAY 1.021277 (-2700 1200);
PAINT ORANGE (-2700 1200);
DISPLAY INVISIBLE (-2700 1200);
FORCEPROP 2 LAST SEC 1
J 0
(-2700 1200);
PAINT MONO (-2700 1200);
DISPLAY INVISIBLE (-2700 1200);
FORCEPROP 1 LAST PATH I2
J 2
(-2700 1150);
DISPLAY 0.978723 (-2700 1150);
PAINT WHITE (-2700 1150);
DISPLAY INVISIBLE (-2700 1150);
FORCEPROP 2 LAST ROOM DDR4_CH_A
J 0
(-2650 1000);
PAINT ORANGE (-2650 1000);
DISPLAY INVISIBLE (-2650 1000);
FORCEADD OFFPAGE..1
(-2100 2650);
FORCEPROP 2 LAST $XR0 23 
J 0
(-2321 2650);
DISPLAY 0.638298 (-2321 2650);
PAINT MONO (-2321 2650);
FORCEPROP 2 LAST $XR1 43 
J 0
(-2411 2650);
DISPLAY 0.638298 (-2411 2650);
PAINT MONO (-2411 2650);
FORCEPROP 2 LAST CDS_LIB mstr_standard
J 0
(-2100 2650);
DISPLAY 0.787234 (-2100 2650);
PAINT MONO (-2100 2650);
DISPLAY INVISIBLE (-2100 2650);
FORCEPROP 1 LAST OFFPAGE TRUE
J 0
(-1775 2525);
DISPLAY 0.936170 (-1775 2525);
PAINT GREEN (-1775 2525);
DISPLAY INVISIBLE (-1775 2525);
FORCEPROP 1 LAST COMMENT_BODY TRUE
J 0
(-1975 2550);
DISPLAY 0.936170 (-1975 2550);
PAINT GREEN (-1975 2550);
DISPLAY INVISIBLE (-1975 2550);
FORCEPROP 2 LAST PATH I20
J 0
(-2300 2700);
DISPLAY 1.021277 (-2300 2700);
PAINT ORANGE (-2300 2700);
DISPLAY INVISIBLE (-2300 2700);
FORCEADD TAP..6
(-1450 2100);
FORCEPROP 3 LASTPIN (-1400 2100) SIG_NAME M_A_ECC<3>
J 0
(-1390 2110);
DISPLAY 0.659574 (-1390 2110);
PAINT MONO (-1390 2110);
DISPLAY INVISIBLE (-1390 2110);
FORCEPROP 1 LASTPIN (-1400 2100) BN 3
J 0
(-1450 2110);
DISPLAY 0.617021 (-1450 2110);
PAINT PINK (-1450 2110);
FORCEPROP 2 LAST CDS_LIB mstr_standard
J 0
(-1450 2100);
DISPLAY 0.787234 (-1450 2100);
PAINT MONO (-1450 2100);
DISPLAY INVISIBLE (-1450 2100);
FORCEPROP 1 LAST BODY_TYPE PLUMBING
J 0
(-1450 2050);
DISPLAY 1.234043 (-1450 2050);
PAINT GREEN (-1450 2050);
DISPLAY INVISIBLE (-1450 2050);
FORCEPROP 1 LAST HDL_TAP TRUE
J 0
(-1125 1975);
DISPLAY 1.234043 (-1125 1975);
PAINT GREEN (-1125 1975);
DISPLAY INVISIBLE (-1125 1975);
FORCEPROP 1 LAST PATH I21
J 0
(-1452 2100);
DISPLAY 0.872340 (-1452 2100);
PAINT GREEN (-1452 2100);
DISPLAY INVISIBLE (-1452 2100);
FORCEADD TAP..6
(-1450 2000);
FORCEPROP 3 LASTPIN (-1400 2000) SIG_NAME M_A_ECC<1>
J 0
(-1390 2010);
DISPLAY 0.659574 (-1390 2010);
PAINT MONO (-1390 2010);
DISPLAY INVISIBLE (-1390 2010);
FORCEPROP 1 LASTPIN (-1400 2000) BN 1
J 0
(-1450 2010);
DISPLAY 0.617021 (-1450 2010);
PAINT PINK (-1450 2010);
FORCEPROP 2 LAST CDS_LIB mstr_standard
J 0
(-1450 2000);
DISPLAY 0.787234 (-1450 2000);
PAINT MONO (-1450 2000);
DISPLAY INVISIBLE (-1450 2000);
FORCEPROP 1 LAST BODY_TYPE PLUMBING
J 0
(-1450 1950);
DISPLAY 1.234043 (-1450 1950);
PAINT GREEN (-1450 1950);
DISPLAY INVISIBLE (-1450 1950);
FORCEPROP 1 LAST HDL_TAP TRUE
J 0
(-1125 1875);
DISPLAY 1.234043 (-1125 1875);
PAINT GREEN (-1125 1875);
DISPLAY INVISIBLE (-1125 1875);
FORCEPROP 1 LAST PATH I22
J 0
(-1452 2000);
DISPLAY 0.872340 (-1452 2000);
PAINT GREEN (-1452 2000);
DISPLAY INVISIBLE (-1452 2000);
FORCEADD TAP..6
(-1450 2050);
FORCEPROP 3 LASTPIN (-1400 2050) SIG_NAME M_A_ECC<2>
J 0
(-1390 2060);
DISPLAY 0.659574 (-1390 2060);
PAINT MONO (-1390 2060);
DISPLAY INVISIBLE (-1390 2060);
FORCEPROP 1 LASTPIN (-1400 2050) BN 2
J 0
(-1450 2060);
DISPLAY 0.617021 (-1450 2060);
PAINT PINK (-1450 2060);
FORCEPROP 2 LAST CDS_LIB mstr_standard
J 0
(-1450 2050);
DISPLAY 0.787234 (-1450 2050);
PAINT MONO (-1450 2050);
DISPLAY INVISIBLE (-1450 2050);
FORCEPROP 1 LAST BODY_TYPE PLUMBING
J 0
(-1450 2000);
DISPLAY 1.234043 (-1450 2000);
PAINT GREEN (-1450 2000);
DISPLAY INVISIBLE (-1450 2000);
FORCEPROP 1 LAST HDL_TAP TRUE
J 0
(-1125 1925);
DISPLAY 1.234043 (-1125 1925);
PAINT GREEN (-1125 1925);
DISPLAY INVISIBLE (-1125 1925);
FORCEPROP 1 LAST PATH I23
J 0
(-1452 2050);
DISPLAY 0.872340 (-1452 2050);
PAINT GREEN (-1452 2050);
DISPLAY INVISIBLE (-1452 2050);
FORCEADD TAP..6
(-1450 2150);
FORCEPROP 3 LASTPIN (-1400 2150) SIG_NAME M_A_ECC<4>
J 0
(-1390 2160);
DISPLAY 0.659574 (-1390 2160);
PAINT MONO (-1390 2160);
DISPLAY INVISIBLE (-1390 2160);
FORCEPROP 1 LASTPIN (-1400 2150) BN 4
J 0
(-1450 2160);
DISPLAY 0.617021 (-1450 2160);
PAINT PINK (-1450 2160);
FORCEPROP 2 LAST CDS_LIB mstr_standard
J 0
(-1450 2150);
DISPLAY 0.787234 (-1450 2150);
PAINT MONO (-1450 2150);
DISPLAY INVISIBLE (-1450 2150);
FORCEPROP 1 LAST BODY_TYPE PLUMBING
J 0
(-1450 2100);
DISPLAY 1.234043 (-1450 2100);
PAINT GREEN (-1450 2100);
DISPLAY INVISIBLE (-1450 2100);
FORCEPROP 1 LAST HDL_TAP TRUE
J 0
(-1125 2025);
DISPLAY 1.234043 (-1125 2025);
PAINT GREEN (-1125 2025);
DISPLAY INVISIBLE (-1125 2025);
FORCEPROP 1 LAST PATH I24
J 0
(-1452 2150);
DISPLAY 0.872340 (-1452 2150);
PAINT GREEN (-1452 2150);
DISPLAY INVISIBLE (-1452 2150);
FORCEADD TAP..6
(-1450 2200);
FORCEPROP 3 LASTPIN (-1400 2200) SIG_NAME M_A_ECC<5>
J 0
(-1390 2210);
DISPLAY 0.659574 (-1390 2210);
PAINT MONO (-1390 2210);
DISPLAY INVISIBLE (-1390 2210);
FORCEPROP 1 LASTPIN (-1400 2200) BN 5
J 0
(-1450 2210);
DISPLAY 0.617021 (-1450 2210);
PAINT PINK (-1450 2210);
FORCEPROP 2 LAST CDS_LIB mstr_standard
J 0
(-1450 2200);
DISPLAY 0.787234 (-1450 2200);
PAINT MONO (-1450 2200);
DISPLAY INVISIBLE (-1450 2200);
FORCEPROP 1 LAST BODY_TYPE PLUMBING
J 0
(-1450 2150);
DISPLAY 1.234043 (-1450 2150);
PAINT GREEN (-1450 2150);
DISPLAY INVISIBLE (-1450 2150);
FORCEPROP 1 LAST HDL_TAP TRUE
J 0
(-1125 2075);
DISPLAY 1.234043 (-1125 2075);
PAINT GREEN (-1125 2075);
DISPLAY INVISIBLE (-1125 2075);
FORCEPROP 1 LAST PATH I25
J 0
(-1452 2200);
DISPLAY 0.872340 (-1452 2200);
PAINT GREEN (-1452 2200);
DISPLAY INVISIBLE (-1452 2200);
FORCEADD TAP..6
(-1450 2250);
FORCEPROP 3 LASTPIN (-1400 2250) SIG_NAME M_A_ECC<6>
J 0
(-1390 2260);
DISPLAY 0.659574 (-1390 2260);
PAINT MONO (-1390 2260);
DISPLAY INVISIBLE (-1390 2260);
FORCEPROP 1 LASTPIN (-1400 2250) BN 6
J 0
(-1450 2260);
DISPLAY 0.617021 (-1450 2260);
PAINT PINK (-1450 2260);
FORCEPROP 2 LAST CDS_LIB mstr_standard
J 0
(-1450 2250);
DISPLAY 0.787234 (-1450 2250);
PAINT MONO (-1450 2250);
DISPLAY INVISIBLE (-1450 2250);
FORCEPROP 1 LAST BODY_TYPE PLUMBING
J 0
(-1450 2200);
DISPLAY 1.234043 (-1450 2200);
PAINT GREEN (-1450 2200);
DISPLAY INVISIBLE (-1450 2200);
FORCEPROP 1 LAST HDL_TAP TRUE
J 0
(-1125 2125);
DISPLAY 1.234043 (-1125 2125);
PAINT GREEN (-1125 2125);
DISPLAY INVISIBLE (-1125 2125);
FORCEPROP 1 LAST PATH I26
J 0
(-1452 2250);
DISPLAY 0.872340 (-1452 2250);
PAINT GREEN (-1452 2250);
DISPLAY INVISIBLE (-1452 2250);
FORCEADD TAP..6
(-1450 2400);
FORCEPROP 3 LASTPIN (-1400 2400) SIG_NAME M_A_ODT<2>
J 0
(-1390 2410);
DISPLAY 0.659574 (-1390 2410);
PAINT MONO (-1390 2410);
DISPLAY INVISIBLE (-1390 2410);
FORCEPROP 1 LASTPIN (-1400 2400) BN 2
J 0
(-1450 2410);
DISPLAY 0.617021 (-1450 2410);
PAINT PINK (-1450 2410);
FORCEPROP 2 LAST CDS_LIB mstr_standard
J 0
(-1450 2400);
DISPLAY 0.787234 (-1450 2400);
PAINT MONO (-1450 2400);
DISPLAY INVISIBLE (-1450 2400);
FORCEPROP 1 LAST BODY_TYPE PLUMBING
J 0
(-1450 2350);
DISPLAY 1.234043 (-1450 2350);
PAINT GREEN (-1450 2350);
DISPLAY INVISIBLE (-1450 2350);
FORCEPROP 1 LAST HDL_TAP TRUE
J 0
(-1125 2275);
DISPLAY 1.234043 (-1125 2275);
PAINT GREEN (-1125 2275);
DISPLAY INVISIBLE (-1125 2275);
FORCEPROP 1 LAST PATH I27
J 0
(-1452 2400);
DISPLAY 0.872340 (-1452 2400);
PAINT GREEN (-1452 2400);
DISPLAY INVISIBLE (-1452 2400);
FORCEADD TAP..6
(-1450 2450);
FORCEPROP 3 LASTPIN (-1400 2450) SIG_NAME M_A_ODT<3>
J 0
(-1390 2460);
DISPLAY 0.659574 (-1390 2460);
PAINT MONO (-1390 2460);
DISPLAY INVISIBLE (-1390 2460);
FORCEPROP 1 LASTPIN (-1400 2450) BN 3
J 0
(-1450 2460);
DISPLAY 0.617021 (-1450 2460);
PAINT PINK (-1450 2460);
FORCEPROP 2 LAST CDS_LIB mstr_standard
J 0
(-1450 2450);
DISPLAY 0.787234 (-1450 2450);
PAINT MONO (-1450 2450);
DISPLAY INVISIBLE (-1450 2450);
FORCEPROP 1 LAST BODY_TYPE PLUMBING
J 0
(-1450 2400);
DISPLAY 1.234043 (-1450 2400);
PAINT GREEN (-1450 2400);
DISPLAY INVISIBLE (-1450 2400);
FORCEPROP 1 LAST HDL_TAP TRUE
J 0
(-1125 2325);
DISPLAY 1.234043 (-1125 2325);
PAINT GREEN (-1125 2325);
DISPLAY INVISIBLE (-1125 2325);
FORCEPROP 1 LAST PATH I28
J 0
(-1452 2450);
DISPLAY 0.872340 (-1452 2450);
PAINT GREEN (-1452 2450);
DISPLAY INVISIBLE (-1452 2450);
FORCEADD TAP..6
(-1450 2300);
FORCEPROP 3 LASTPIN (-1400 2300) SIG_NAME M_A_ECC<7>
J 0
(-1390 2310);
DISPLAY 0.659574 (-1390 2310);
PAINT MONO (-1390 2310);
DISPLAY INVISIBLE (-1390 2310);
FORCEPROP 1 LASTPIN (-1400 2300) BN 7
J 0
(-1450 2310);
DISPLAY 0.617021 (-1450 2310);
PAINT PINK (-1450 2310);
FORCEPROP 2 LAST CDS_LIB mstr_standard
J 0
(-1450 2300);
DISPLAY 0.787234 (-1450 2300);
PAINT MONO (-1450 2300);
DISPLAY INVISIBLE (-1450 2300);
FORCEPROP 1 LAST BODY_TYPE PLUMBING
J 0
(-1450 2250);
DISPLAY 1.234043 (-1450 2250);
PAINT GREEN (-1450 2250);
DISPLAY INVISIBLE (-1450 2250);
FORCEPROP 1 LAST HDL_TAP TRUE
J 0
(-1125 2175);
DISPLAY 1.234043 (-1125 2175);
PAINT GREEN (-1125 2175);
DISPLAY INVISIBLE (-1125 2175);
FORCEPROP 1 LAST PATH I29
J 0
(-1452 2300);
DISPLAY 0.872340 (-1452 2300);
PAINT GREEN (-1452 2300);
DISPLAY INVISIBLE (-1452 2300);
FORCEADD GND..1
R 2
(-3350 1350);
FORCEPROP 3 LASTPIN (-3350 1400) SIG_NAME GND\g
J 0
(-3340 1410);
DISPLAY 0.659574 (-3340 1410);
PAINT MONO (-3340 1410);
DISPLAY INVISIBLE (-3340 1410);
FORCEPROP 1 LAST VOLTAGE 0
J 0
(-3350 1350);
PAINT SKYBLUE (-3350 1350);
DISPLAY INVISIBLE (-3350 1350);
FORCEPROP 1 LAST SIZE 1B
J 2
(-3425 1300);
DISPLAY 1.170213 (-3425 1300);
PAINT GREEN (-3425 1300);
DISPLAY INVISIBLE (-3425 1300);
FORCEPROP 2 LAST CDS_LIB mstr_symbols
J 0
(-3350 1350);
DISPLAY 0.787234 (-3350 1350);
PAINT MONO (-3350 1350);
DISPLAY INVISIBLE (-3350 1350);
FORCEPROP 2 LAST BOM_COST MEM
J 0
(-3350 1355);
PAINT ORANGE (-3350 1355);
DISPLAY INVISIBLE (-3350 1355);
FORCEPROP 1 LAST BODY_TYPE PLUMBING
J 2
(-3305 1307);
DISPLAY 0.340426 (-3305 1307);
PAINT GREEN (-3305 1307);
DISPLAY INVISIBLE (-3305 1307);
FORCEPROP 1 LAST PATH I3
J 2
(-3425 1350);
DISPLAY 0.872340 (-3425 1350);
PAINT AQUA (-3425 1350);
DISPLAY INVISIBLE (-3425 1350);
FORCEPROP 2 LAST ROOM DDR4_CH_A
J 0
(-3350 1355);
PAINT ORANGE (-3350 1355);
DISPLAY INVISIBLE (-3350 1355);
FORCEPROP 1 LAST HDL_POWER GND
J 2
(-3350 1500);
DISPLAY 0.553191 (-3350 1500);
PAINT GREEN (-3350 1500);
DISPLAY INVISIBLE (-3350 1500);
FORCEADD TAP..6
(-1650 3000);
FORCEPROP 3 LASTPIN (-1600 3000) SIG_NAME M_A_CLK_DN<2>
J 0
(-1590 3010);
DISPLAY 0.659574 (-1590 3010);
PAINT MONO (-1590 3010);
DISPLAY INVISIBLE (-1590 3010);
FORCEPROP 1 LASTPIN (-1600 3000) BN 2
J 0
(-1650 3010);
DISPLAY 0.617021 (-1650 3010);
PAINT PINK (-1650 3010);
FORCEPROP 2 LAST CDS_LIB mstr_standard
J 0
(-1650 3000);
DISPLAY 0.787234 (-1650 3000);
PAINT MONO (-1650 3000);
DISPLAY INVISIBLE (-1650 3000);
FORCEPROP 1 LAST BODY_TYPE PLUMBING
J 0
(-1650 2950);
DISPLAY 1.234043 (-1650 2950);
PAINT GREEN (-1650 2950);
DISPLAY INVISIBLE (-1650 2950);
FORCEPROP 1 LAST HDL_TAP TRUE
J 0
(-1325 2875);
DISPLAY 1.234043 (-1325 2875);
PAINT GREEN (-1325 2875);
DISPLAY INVISIBLE (-1325 2875);
FORCEPROP 1 LAST PATH I30
J 0
(-1652 3000);
DISPLAY 0.872340 (-1652 3000);
PAINT GREEN (-1652 3000);
DISPLAY INVISIBLE (-1652 3000);
FORCEADD TAP..6
(-1450 2600);
FORCEPROP 3 LASTPIN (-1400 2600) SIG_NAME M_A_CKE<3>
J 0
(-1390 2610);
DISPLAY 0.659574 (-1390 2610);
PAINT MONO (-1390 2610);
DISPLAY INVISIBLE (-1390 2610);
FORCEPROP 1 LASTPIN (-1400 2600) BN 3
J 0
(-1450 2610);
DISPLAY 0.617021 (-1450 2610);
PAINT PINK (-1450 2610);
FORCEPROP 2 LAST CDS_LIB mstr_standard
J 0
(-1450 2600);
DISPLAY 0.787234 (-1450 2600);
PAINT MONO (-1450 2600);
DISPLAY INVISIBLE (-1450 2600);
FORCEPROP 1 LAST BODY_TYPE PLUMBING
J 0
(-1450 2550);
DISPLAY 1.234043 (-1450 2550);
PAINT GREEN (-1450 2550);
DISPLAY INVISIBLE (-1450 2550);
FORCEPROP 1 LAST HDL_TAP TRUE
J 0
(-1125 2475);
DISPLAY 1.234043 (-1125 2475);
PAINT GREEN (-1125 2475);
DISPLAY INVISIBLE (-1125 2475);
FORCEPROP 1 LAST PATH I31
J 0
(-1452 2600);
DISPLAY 0.872340 (-1452 2600);
PAINT GREEN (-1452 2600);
DISPLAY INVISIBLE (-1452 2600);
FORCEADD TAP..6
(-1450 2550);
FORCEPROP 3 LASTPIN (-1400 2550) SIG_NAME M_A_CKE<2>
J 0
(-1390 2560);
DISPLAY 0.659574 (-1390 2560);
PAINT MONO (-1390 2560);
DISPLAY INVISIBLE (-1390 2560);
FORCEPROP 1 LASTPIN (-1400 2550) BN 2
J 0
(-1450 2560);
DISPLAY 0.617021 (-1450 2560);
PAINT PINK (-1450 2560);
FORCEPROP 2 LAST CDS_LIB mstr_standard
J 0
(-1450 2550);
DISPLAY 0.787234 (-1450 2550);
PAINT MONO (-1450 2550);
DISPLAY INVISIBLE (-1450 2550);
FORCEPROP 1 LAST BODY_TYPE PLUMBING
J 0
(-1450 2500);
DISPLAY 1.234043 (-1450 2500);
PAINT GREEN (-1450 2500);
DISPLAY INVISIBLE (-1450 2500);
FORCEPROP 1 LAST HDL_TAP TRUE
J 0
(-1125 2425);
DISPLAY 1.234043 (-1125 2425);
PAINT GREEN (-1125 2425);
DISPLAY INVISIBLE (-1125 2425);
FORCEPROP 1 LAST PATH I32
J 0
(-1452 2550);
DISPLAY 0.872340 (-1452 2550);
PAINT GREEN (-1452 2550);
DISPLAY INVISIBLE (-1452 2550);
FORCEADD TAP..6
(-1450 2700);
FORCEPROP 3 LASTPIN (-1400 2700) SIG_NAME M_A_CS_N<4>
J 0
(-1390 2710);
DISPLAY 0.659574 (-1390 2710);
PAINT MONO (-1390 2710);
DISPLAY INVISIBLE (-1390 2710);
FORCEPROP 1 LASTPIN (-1400 2700) BN 4
J 0
(-1450 2710);
DISPLAY 0.617021 (-1450 2710);
PAINT PINK (-1450 2710);
FORCEPROP 2 LAST CDS_LIB mstr_standard
J 0
(-1450 2700);
DISPLAY 0.787234 (-1450 2700);
PAINT MONO (-1450 2700);
DISPLAY INVISIBLE (-1450 2700);
FORCEPROP 1 LAST BODY_TYPE PLUMBING
J 0
(-1450 2650);
DISPLAY 1.234043 (-1450 2650);
PAINT GREEN (-1450 2650);
DISPLAY INVISIBLE (-1450 2650);
FORCEPROP 1 LAST HDL_TAP TRUE
J 0
(-1125 2575);
DISPLAY 1.234043 (-1125 2575);
PAINT GREEN (-1125 2575);
DISPLAY INVISIBLE (-1125 2575);
FORCEPROP 1 LAST PATH I33
J 0
(-1452 2700);
DISPLAY 0.872340 (-1452 2700);
PAINT GREEN (-1452 2700);
DISPLAY INVISIBLE (-1452 2700);
FORCEADD TAP..6
(-1450 2750);
FORCEPROP 3 LASTPIN (-1400 2750) SIG_NAME M_A_CS_N<5>
J 0
(-1390 2760);
DISPLAY 0.659574 (-1390 2760);
PAINT MONO (-1390 2760);
DISPLAY INVISIBLE (-1390 2760);
FORCEPROP 1 LASTPIN (-1400 2750) BN 5
J 0
(-1450 2760);
DISPLAY 0.617021 (-1450 2760);
PAINT PINK (-1450 2760);
FORCEPROP 2 LAST CDS_LIB mstr_standard
J 0
(-1450 2750);
DISPLAY 0.787234 (-1450 2750);
PAINT MONO (-1450 2750);
DISPLAY INVISIBLE (-1450 2750);
FORCEPROP 1 LAST BODY_TYPE PLUMBING
J 0
(-1450 2700);
DISPLAY 1.234043 (-1450 2700);
PAINT GREEN (-1450 2700);
DISPLAY INVISIBLE (-1450 2700);
FORCEPROP 1 LAST HDL_TAP TRUE
J 0
(-1125 2625);
DISPLAY 1.234043 (-1125 2625);
PAINT GREEN (-1125 2625);
DISPLAY INVISIBLE (-1125 2625);
FORCEPROP 1 LAST PATH I34
J 0
(-1452 2750);
DISPLAY 0.872340 (-1452 2750);
PAINT GREEN (-1452 2750);
DISPLAY INVISIBLE (-1452 2750);
FORCEADD TAP..6
(-1450 2850);
FORCEPROP 3 LASTPIN (-1400 2850) SIG_NAME M_A_CS_N<7>
J 0
(-1390 2860);
DISPLAY 0.659574 (-1390 2860);
PAINT MONO (-1390 2860);
DISPLAY INVISIBLE (-1390 2860);
FORCEPROP 1 LASTPIN (-1400 2850) BN 7
J 0
(-1450 2860);
DISPLAY 0.617021 (-1450 2860);
PAINT PINK (-1450 2860);
FORCEPROP 2 LAST CDS_LIB mstr_standard
J 0
(-1450 2850);
DISPLAY 0.787234 (-1450 2850);
PAINT MONO (-1450 2850);
DISPLAY INVISIBLE (-1450 2850);
FORCEPROP 1 LAST BODY_TYPE PLUMBING
J 0
(-1450 2800);
DISPLAY 1.234043 (-1450 2800);
PAINT GREEN (-1450 2800);
DISPLAY INVISIBLE (-1450 2800);
FORCEPROP 1 LAST HDL_TAP TRUE
J 0
(-1125 2725);
DISPLAY 1.234043 (-1125 2725);
PAINT GREEN (-1125 2725);
DISPLAY INVISIBLE (-1125 2725);
FORCEPROP 1 LAST PATH I35
J 0
(-1452 2850);
DISPLAY 0.872340 (-1452 2850);
PAINT GREEN (-1452 2850);
DISPLAY INVISIBLE (-1452 2850);
FORCEADD TAP..6
(-1450 2800);
FORCEPROP 3 LASTPIN (-1400 2800) SIG_NAME M_A_CS_N<6>
J 0
(-1390 2810);
DISPLAY 0.659574 (-1390 2810);
PAINT MONO (-1390 2810);
DISPLAY INVISIBLE (-1390 2810);
FORCEPROP 1 LASTPIN (-1400 2800) BN 6
J 0
(-1450 2810);
DISPLAY 0.617021 (-1450 2810);
PAINT PINK (-1450 2810);
FORCEPROP 2 LAST CDS_LIB mstr_standard
J 0
(-1450 2800);
DISPLAY 0.787234 (-1450 2800);
PAINT MONO (-1450 2800);
DISPLAY INVISIBLE (-1450 2800);
FORCEPROP 1 LAST BODY_TYPE PLUMBING
J 0
(-1450 2750);
DISPLAY 1.234043 (-1450 2750);
PAINT GREEN (-1450 2750);
DISPLAY INVISIBLE (-1450 2750);
FORCEPROP 1 LAST HDL_TAP TRUE
J 0
(-1125 2675);
DISPLAY 1.234043 (-1125 2675);
PAINT GREEN (-1125 2675);
DISPLAY INVISIBLE (-1125 2675);
FORCEPROP 1 LAST PATH I36
J 0
(-1452 2800);
DISPLAY 0.872340 (-1452 2800);
PAINT GREEN (-1452 2800);
DISPLAY INVISIBLE (-1452 2800);
FORCEADD OFFPAGE..1
(-2100 3200);
FORCEPROP 2 LAST $XR0 23 
J 0
(-2321 3200);
DISPLAY 0.638298 (-2321 3200);
PAINT MONO (-2321 3200);
FORCEPROP 2 LAST $XR1 43 
J 0
(-2411 3200);
DISPLAY 0.638298 (-2411 3200);
PAINT MONO (-2411 3200);
FORCEPROP 2 LAST CDS_LIB mstr_standard
J 0
(-2100 3200);
DISPLAY 0.787234 (-2100 3200);
PAINT MONO (-2100 3200);
DISPLAY INVISIBLE (-2100 3200);
FORCEPROP 1 LAST OFFPAGE TRUE
J 0
(-1775 3075);
DISPLAY 0.936170 (-1775 3075);
PAINT GREEN (-1775 3075);
DISPLAY INVISIBLE (-1775 3075);
FORCEPROP 1 LAST COMMENT_BODY TRUE
J 0
(-1975 3100);
DISPLAY 0.936170 (-1975 3100);
PAINT GREEN (-1975 3100);
DISPLAY INVISIBLE (-1975 3100);
FORCEPROP 2 LAST PATH I37
J 0
(-2300 3250);
DISPLAY 1.021277 (-2300 3250);
PAINT ORANGE (-2300 3250);
DISPLAY INVISIBLE (-2300 3250);
FORCEADD OFFPAGE..1
(-2100 3150);
FORCEPROP 2 LAST $XR0 23 
J 0
(-2321 3150);
DISPLAY 0.638298 (-2321 3150);
PAINT MONO (-2321 3150);
FORCEPROP 2 LAST $XR1 43 
J 0
(-2411 3150);
DISPLAY 0.638298 (-2411 3150);
PAINT MONO (-2411 3150);
FORCEPROP 2 LAST CDS_LIB mstr_standard
J 0
(-2100 3150);
DISPLAY 0.787234 (-2100 3150);
PAINT MONO (-2100 3150);
DISPLAY INVISIBLE (-2100 3150);
FORCEPROP 1 LAST OFFPAGE TRUE
J 0
(-1775 3025);
DISPLAY 0.936170 (-1775 3025);
PAINT GREEN (-1775 3025);
DISPLAY INVISIBLE (-1775 3025);
FORCEPROP 1 LAST COMMENT_BODY TRUE
J 0
(-1975 3050);
DISPLAY 0.936170 (-1975 3050);
PAINT GREEN (-1975 3050);
DISPLAY INVISIBLE (-1975 3050);
FORCEPROP 2 LAST PATH I38
J 0
(-2300 3200);
DISPLAY 1.021277 (-2300 3200);
PAINT ORANGE (-2300 3200);
DISPLAY INVISIBLE (-2300 3200);
FORCEADD OFFPAGE..1
(-2100 3350);
FORCEPROP 2 LAST $XR0 23 
J 0
(-2321 3350);
DISPLAY 0.638298 (-2321 3350);
PAINT MONO (-2321 3350);
FORCEPROP 2 LAST $XR1 43 
J 0
(-2411 3350);
DISPLAY 0.638298 (-2411 3350);
PAINT MONO (-2411 3350);
FORCEPROP 2 LAST CDS_LIB mstr_standard
J 0
(-2100 3350);
DISPLAY 0.787234 (-2100 3350);
PAINT MONO (-2100 3350);
DISPLAY INVISIBLE (-2100 3350);
FORCEPROP 1 LAST OFFPAGE TRUE
J 0
(-1775 3225);
DISPLAY 0.936170 (-1775 3225);
PAINT GREEN (-1775 3225);
DISPLAY INVISIBLE (-1775 3225);
FORCEPROP 1 LAST COMMENT_BODY TRUE
J 0
(-1975 3250);
DISPLAY 0.936170 (-1975 3250);
PAINT GREEN (-1975 3250);
DISPLAY INVISIBLE (-1975 3250);
FORCEPROP 2 LAST PATH I39
J 0
(-2300 3400);
DISPLAY 1.021277 (-2300 3400);
PAINT ORANGE (-2300 3400);
DISPLAY INVISIBLE (-2300 3400);
FORCEADD OFFPAGE..1
(-2800 1200);
FORCEPROP 2 LAST $XR0 98 
J 0
(-3051 1200);
DISPLAY 0.638298 (-3051 1200);
PAINT MONO (-3051 1200);
FORCEPROP 2 LAST $XR1 43 
J 0
(-3141 1200);
DISPLAY 0.638298 (-3141 1200);
PAINT MONO (-3141 1200);
FORCEPROP 2 LAST CDS_LIB mstr_standard
J 0
(-2800 1200);
DISPLAY 0.787234 (-2800 1200);
PAINT MONO (-2800 1200);
DISPLAY INVISIBLE (-2800 1200);
FORCEPROP 1 LAST OFFPAGE TRUE
J 0
(-2475 1075);
DISPLAY 0.936170 (-2475 1075);
PAINT GREEN (-2475 1075);
DISPLAY INVISIBLE (-2475 1075);
FORCEPROP 1 LAST COMMENT_BODY TRUE
J 0
(-2675 1100);
DISPLAY 0.936170 (-2675 1100);
PAINT GREEN (-2675 1100);
DISPLAY INVISIBLE (-2675 1100);
FORCEPROP 2 LAST PATH I4
J 0
(-3050 1250);
DISPLAY 1.021277 (-3050 1250);
PAINT ORANGE (-3050 1250);
DISPLAY INVISIBLE (-3050 1250);
FORCEADD OFFPAGE..1
(-2100 3450);
FORCEPROP 2 LAST $XR0 23 
J 0
(-2321 3450);
DISPLAY 0.638298 (-2321 3450);
PAINT MONO (-2321 3450);
FORCEPROP 2 LAST $XR1 43 
J 0
(-2411 3450);
DISPLAY 0.638298 (-2411 3450);
PAINT MONO (-2411 3450);
FORCEPROP 2 LAST CDS_LIB mstr_standard
J 0
(-2100 3450);
DISPLAY 0.787234 (-2100 3450);
PAINT MONO (-2100 3450);
DISPLAY INVISIBLE (-2100 3450);
FORCEPROP 1 LAST OFFPAGE TRUE
J 0
(-1775 3325);
DISPLAY 0.936170 (-1775 3325);
PAINT GREEN (-1775 3325);
DISPLAY INVISIBLE (-1775 3325);
FORCEPROP 1 LAST COMMENT_BODY TRUE
J 0
(-1975 3350);
DISPLAY 0.936170 (-1975 3350);
PAINT GREEN (-1975 3350);
DISPLAY INVISIBLE (-1975 3350);
FORCEPROP 2 LAST PATH I40
J 0
(-2300 3500);
DISPLAY 1.021277 (-2300 3500);
PAINT ORANGE (-2300 3500);
DISPLAY INVISIBLE (-2300 3500);
FORCEADD TAP..6
(-1650 3100);
FORCEPROP 3 LASTPIN (-1600 3100) SIG_NAME M_A_CLK_DN<3>
J 0
(-1590 3110);
DISPLAY 0.659574 (-1590 3110);
PAINT MONO (-1590 3110);
DISPLAY INVISIBLE (-1590 3110);
FORCEPROP 1 LASTPIN (-1600 3100) BN 3
J 0
(-1650 3110);
DISPLAY 0.617021 (-1650 3110);
PAINT PINK (-1650 3110);
FORCEPROP 2 LAST CDS_LIB mstr_standard
J 0
(-1650 3100);
DISPLAY 0.787234 (-1650 3100);
PAINT MONO (-1650 3100);
DISPLAY INVISIBLE (-1650 3100);
FORCEPROP 1 LAST BODY_TYPE PLUMBING
J 0
(-1650 3050);
DISPLAY 1.234043 (-1650 3050);
PAINT GREEN (-1650 3050);
DISPLAY INVISIBLE (-1650 3050);
FORCEPROP 1 LAST HDL_TAP TRUE
J 0
(-1325 2975);
DISPLAY 1.234043 (-1325 2975);
PAINT GREEN (-1325 2975);
DISPLAY INVISIBLE (-1325 2975);
FORCEPROP 1 LAST PATH I41
J 0
(-1652 3100);
DISPLAY 0.872340 (-1652 3100);
PAINT GREEN (-1652 3100);
DISPLAY INVISIBLE (-1652 3100);
FORCEADD TAP..6
(-1450 3150);
FORCEPROP 3 LASTPIN (-1400 3150) SIG_NAME M_A_CLK_DP<3>
J 0
(-1390 3160);
DISPLAY 0.659574 (-1390 3160);
PAINT MONO (-1390 3160);
DISPLAY INVISIBLE (-1390 3160);
FORCEPROP 1 LASTPIN (-1400 3150) BN 3
J 0
(-1450 3160);
DISPLAY 0.617021 (-1450 3160);
PAINT PINK (-1450 3160);
FORCEPROP 2 LAST CDS_LIB mstr_standard
J 0
(-1450 3150);
DISPLAY 0.787234 (-1450 3150);
PAINT MONO (-1450 3150);
DISPLAY INVISIBLE (-1450 3150);
FORCEPROP 1 LAST BODY_TYPE PLUMBING
J 0
(-1450 3100);
DISPLAY 1.234043 (-1450 3100);
PAINT GREEN (-1450 3100);
DISPLAY INVISIBLE (-1450 3100);
FORCEPROP 1 LAST HDL_TAP TRUE
J 0
(-1125 3025);
DISPLAY 1.234043 (-1125 3025);
PAINT GREEN (-1125 3025);
DISPLAY INVISIBLE (-1125 3025);
FORCEPROP 1 LAST PATH I42
J 0
(-1452 3150);
DISPLAY 0.872340 (-1452 3150);
PAINT GREEN (-1452 3150);
DISPLAY INVISIBLE (-1452 3150);
FORCEADD TAP..6
(-1450 3050);
FORCEPROP 3 LASTPIN (-1400 3050) SIG_NAME M_A_CLK_DP<2>
J 0
(-1390 3060);
DISPLAY 0.659574 (-1390 3060);
PAINT MONO (-1390 3060);
DISPLAY INVISIBLE (-1390 3060);
FORCEPROP 1 LASTPIN (-1400 3050) BN 2
J 0
(-1450 3060);
DISPLAY 0.617021 (-1450 3060);
PAINT PINK (-1450 3060);
FORCEPROP 2 LAST CDS_LIB mstr_standard
J 0
(-1450 3050);
DISPLAY 0.787234 (-1450 3050);
PAINT MONO (-1450 3050);
DISPLAY INVISIBLE (-1450 3050);
FORCEPROP 1 LAST BODY_TYPE PLUMBING
J 0
(-1450 3000);
DISPLAY 1.234043 (-1450 3000);
PAINT GREEN (-1450 3000);
DISPLAY INVISIBLE (-1450 3000);
FORCEPROP 1 LAST HDL_TAP TRUE
J 0
(-1125 2925);
DISPLAY 1.234043 (-1125 2925);
PAINT GREEN (-1125 2925);
DISPLAY INVISIBLE (-1125 2925);
FORCEPROP 1 LAST PATH I43
J 0
(-1452 3050);
DISPLAY 0.872340 (-1452 3050);
PAINT GREEN (-1452 3050);
DISPLAY INVISIBLE (-1452 3050);
FORCEADD TAP..6
(-1450 3250);
FORCEPROP 3 LASTPIN (-1400 3250) SIG_NAME M_A_BG<0>
J 0
(-1390 3260);
DISPLAY 0.659574 (-1390 3260);
PAINT MONO (-1390 3260);
DISPLAY INVISIBLE (-1390 3260);
FORCEPROP 1 LASTPIN (-1400 3250) BN 0
J 0
(-1450 3260);
DISPLAY 0.617021 (-1450 3260);
PAINT PINK (-1450 3260);
FORCEPROP 2 LAST CDS_LIB mstr_standard
J 0
(-1450 3250);
DISPLAY 0.787234 (-1450 3250);
PAINT MONO (-1450 3250);
DISPLAY INVISIBLE (-1450 3250);
FORCEPROP 1 LAST BODY_TYPE PLUMBING
J 0
(-1450 3200);
DISPLAY 1.234043 (-1450 3200);
PAINT GREEN (-1450 3200);
DISPLAY INVISIBLE (-1450 3200);
FORCEPROP 1 LAST HDL_TAP TRUE
J 0
(-1125 3125);
DISPLAY 1.234043 (-1125 3125);
PAINT GREEN (-1125 3125);
DISPLAY INVISIBLE (-1125 3125);
FORCEPROP 1 LAST PATH I44
J 0
(-1452 3250);
DISPLAY 0.872340 (-1452 3250);
PAINT GREEN (-1452 3250);
DISPLAY INVISIBLE (-1452 3250);
FORCEADD TAP..6
(-1450 3300);
FORCEPROP 3 LASTPIN (-1400 3300) SIG_NAME M_A_BG<1>
J 0
(-1390 3310);
DISPLAY 0.659574 (-1390 3310);
PAINT MONO (-1390 3310);
DISPLAY INVISIBLE (-1390 3310);
FORCEPROP 1 LASTPIN (-1400 3300) BN 1
J 0
(-1450 3310);
DISPLAY 0.617021 (-1450 3310);
PAINT PINK (-1450 3310);
FORCEPROP 2 LAST CDS_LIB mstr_standard
J 0
(-1450 3300);
DISPLAY 0.787234 (-1450 3300);
PAINT MONO (-1450 3300);
DISPLAY INVISIBLE (-1450 3300);
FORCEPROP 1 LAST BODY_TYPE PLUMBING
J 0
(-1450 3250);
DISPLAY 1.234043 (-1450 3250);
PAINT GREEN (-1450 3250);
DISPLAY INVISIBLE (-1450 3250);
FORCEPROP 1 LAST HDL_TAP TRUE
J 0
(-1125 3175);
DISPLAY 1.234043 (-1125 3175);
PAINT GREEN (-1125 3175);
DISPLAY INVISIBLE (-1125 3175);
FORCEPROP 1 LAST PATH I45
J 0
(-1452 3300);
DISPLAY 0.872340 (-1452 3300);
PAINT GREEN (-1452 3300);
DISPLAY INVISIBLE (-1452 3300);
FORCEADD TAP..6
(-1450 3400);
FORCEPROP 3 LASTPIN (-1400 3400) SIG_NAME M_A_BA<1>
J 0
(-1390 3410);
DISPLAY 0.659574 (-1390 3410);
PAINT MONO (-1390 3410);
DISPLAY INVISIBLE (-1390 3410);
FORCEPROP 1 LASTPIN (-1400 3400) BN 1
J 0
(-1450 3410);
DISPLAY 0.617021 (-1450 3410);
PAINT PINK (-1450 3410);
FORCEPROP 2 LAST CDS_LIB mstr_standard
J 0
(-1450 3400);
DISPLAY 0.787234 (-1450 3400);
PAINT MONO (-1450 3400);
DISPLAY INVISIBLE (-1450 3400);
FORCEPROP 1 LAST BODY_TYPE PLUMBING
J 0
(-1450 3350);
DISPLAY 1.234043 (-1450 3350);
PAINT GREEN (-1450 3350);
DISPLAY INVISIBLE (-1450 3350);
FORCEPROP 1 LAST HDL_TAP TRUE
J 0
(-1125 3275);
DISPLAY 1.234043 (-1125 3275);
PAINT GREEN (-1125 3275);
DISPLAY INVISIBLE (-1125 3275);
FORCEPROP 1 LAST PATH I46
J 0
(-1452 3400);
DISPLAY 0.872340 (-1452 3400);
PAINT GREEN (-1452 3400);
DISPLAY INVISIBLE (-1452 3400);
FORCEADD TAP..6
(-1450 3350);
FORCEPROP 3 LASTPIN (-1400 3350) SIG_NAME M_A_BA<0>
J 0
(-1390 3360);
DISPLAY 0.659574 (-1390 3360);
PAINT MONO (-1390 3360);
DISPLAY INVISIBLE (-1390 3360);
FORCEPROP 1 LASTPIN (-1400 3350) BN 0
J 0
(-1450 3360);
DISPLAY 0.617021 (-1450 3360);
PAINT PINK (-1450 3360);
FORCEPROP 2 LAST CDS_LIB mstr_standard
J 0
(-1450 3350);
DISPLAY 0.787234 (-1450 3350);
PAINT MONO (-1450 3350);
DISPLAY INVISIBLE (-1450 3350);
FORCEPROP 1 LAST BODY_TYPE PLUMBING
J 0
(-1450 3300);
DISPLAY 1.234043 (-1450 3300);
PAINT GREEN (-1450 3300);
DISPLAY INVISIBLE (-1450 3300);
FORCEPROP 1 LAST HDL_TAP TRUE
J 0
(-1125 3225);
DISPLAY 1.234043 (-1125 3225);
PAINT GREEN (-1125 3225);
DISPLAY INVISIBLE (-1125 3225);
FORCEPROP 1 LAST PATH I47
J 0
(-1452 3350);
DISPLAY 0.872340 (-1452 3350);
PAINT GREEN (-1452 3350);
DISPLAY INVISIBLE (-1452 3350);
FORCEADD TAP..6
(-1450 3500);
FORCEPROP 3 LASTPIN (-1400 3500) SIG_NAME M_A_MA<0>
J 0
(-1390 3510);
DISPLAY 0.659574 (-1390 3510);
PAINT MONO (-1390 3510);
DISPLAY INVISIBLE (-1390 3510);
FORCEPROP 1 LASTPIN (-1400 3500) BN 0
J 0
(-1450 3510);
DISPLAY 0.617021 (-1450 3510);
PAINT PINK (-1450 3510);
FORCEPROP 2 LAST CDS_LIB mstr_standard
J 2
(-1450 3500);
DISPLAY 0.787234 (-1450 3500);
PAINT MONO (-1450 3500);
DISPLAY INVISIBLE (-1450 3500);
FORCEPROP 1 LAST BODY_TYPE PLUMBING
J 0
(-1450 3450);
DISPLAY 1.234043 (-1450 3450);
PAINT GREEN (-1450 3450);
DISPLAY INVISIBLE (-1450 3450);
FORCEPROP 1 LAST HDL_TAP TRUE
J 0
(-1125 3375);
DISPLAY 1.234043 (-1125 3375);
PAINT GREEN (-1125 3375);
DISPLAY INVISIBLE (-1125 3375);
FORCEPROP 1 LAST PATH I48
J 0
(-1452 3500);
DISPLAY 0.872340 (-1452 3500);
PAINT GREEN (-1452 3500);
DISPLAY INVISIBLE (-1452 3500);
FORCEADD TAP..6
(-1450 3700);
FORCEPROP 3 LASTPIN (-1400 3700) SIG_NAME M_A_MA<4>
J 0
(-1390 3710);
DISPLAY 0.659574 (-1390 3710);
PAINT MONO (-1390 3710);
DISPLAY INVISIBLE (-1390 3710);
FORCEPROP 1 LASTPIN (-1400 3700) BN 4
J 0
(-1450 3710);
DISPLAY 0.617021 (-1450 3710);
PAINT PINK (-1450 3710);
FORCEPROP 2 LAST CDS_LIB mstr_standard
J 2
(-1450 3700);
DISPLAY 0.787234 (-1450 3700);
PAINT MONO (-1450 3700);
DISPLAY INVISIBLE (-1450 3700);
FORCEPROP 1 LAST BODY_TYPE PLUMBING
J 0
(-1450 3650);
DISPLAY 1.234043 (-1450 3650);
PAINT GREEN (-1450 3650);
DISPLAY INVISIBLE (-1450 3650);
FORCEPROP 1 LAST HDL_TAP TRUE
J 0
(-1125 3575);
DISPLAY 1.234043 (-1125 3575);
PAINT GREEN (-1125 3575);
DISPLAY INVISIBLE (-1125 3575);
FORCEPROP 1 LAST PATH I49
J 0
(-1452 3700);
DISPLAY 0.872340 (-1452 3700);
PAINT GREEN (-1452 3700);
DISPLAY INVISIBLE (-1452 3700);
FORCEADD PVPP_ABC..1
(-3350 1700);
FORCEPROP 3 LASTPIN (-3350 1650) SIG_NAME PVPP_ABC\g
J 0
(-3340 1660);
DISPLAY 0.659574 (-3340 1660);
PAINT MONO (-3340 1660);
DISPLAY INVISIBLE (-3340 1660);
FORCEPROP 1 LAST VOLTAGE 2.5V
J 0
(-3395 1657);
DISPLAY 0.340426 (-3395 1657);
PAINT SKYBLUE (-3395 1657);
DISPLAY INVISIBLE (-3395 1657);
FORCEPROP 0 LAST BOM_COST MEM
J 0
(-3350 1800);
PAINT ORANGE (-3350 1800);
DISPLAY INVISIBLE (-3350 1800);
FORCEPROP 2 LAST CDS_LIB mstr_symbols
J 0
(-3350 1700);
PAINT ORANGE (-3350 1700);
DISPLAY INVISIBLE (-3350 1700);
FORCEPROP 1 LAST BODY_TYPE PLUMBING
J 0
(-3395 1657);
DISPLAY 0.340426 (-3395 1657);
PAINT GREEN (-3395 1657);
DISPLAY INVISIBLE (-3395 1657);
FORCEPROP 1 LAST PATH I5
J 0
(-3300 1725);
DISPLAY 0.872340 (-3300 1725);
PAINT AQUA (-3300 1725);
DISPLAY INVISIBLE (-3300 1725);
FORCEPROP 2 LAST ROOM DDR4_CH_A
J 0
(-3350 1800);
PAINT ORANGE (-3350 1800);
DISPLAY INVISIBLE (-3350 1800);
FORCEPROP 1 LAST HDL_POWER PVPP_ABC
J 1
(-3350 1750);
DISPLAY 0.872340 (-3350 1750);
PAINT GREEN (-3350 1750);
DISPLAY INVISIBLE (-3350 1750);
FORCEADD TAP..6
(-1450 3600);
FORCEPROP 3 LASTPIN (-1400 3600) SIG_NAME M_A_MA<2>
J 0
(-1390 3610);
DISPLAY 0.659574 (-1390 3610);
PAINT MONO (-1390 3610);
DISPLAY INVISIBLE (-1390 3610);
FORCEPROP 1 LASTPIN (-1400 3600) BN 2
J 0
(-1450 3610);
DISPLAY 0.617021 (-1450 3610);
PAINT PINK (-1450 3610);
FORCEPROP 2 LAST CDS_LIB mstr_standard
J 2
(-1450 3600);
DISPLAY 0.787234 (-1450 3600);
PAINT MONO (-1450 3600);
DISPLAY INVISIBLE (-1450 3600);
FORCEPROP 1 LAST BODY_TYPE PLUMBING
J 0
(-1450 3550);
DISPLAY 1.234043 (-1450 3550);
PAINT GREEN (-1450 3550);
DISPLAY INVISIBLE (-1450 3550);
FORCEPROP 1 LAST HDL_TAP TRUE
J 0
(-1125 3475);
DISPLAY 1.234043 (-1125 3475);
PAINT GREEN (-1125 3475);
DISPLAY INVISIBLE (-1125 3475);
FORCEPROP 1 LAST PATH I50
J 0
(-1452 3600);
DISPLAY 0.872340 (-1452 3600);
PAINT GREEN (-1452 3600);
DISPLAY INVISIBLE (-1452 3600);
FORCEADD TAP..6
(-1450 3550);
FORCEPROP 3 LASTPIN (-1400 3550) SIG_NAME M_A_MA<1>
J 0
(-1390 3560);
DISPLAY 0.659574 (-1390 3560);
PAINT MONO (-1390 3560);
DISPLAY INVISIBLE (-1390 3560);
FORCEPROP 1 LASTPIN (-1400 3550) BN 1
J 0
(-1450 3560);
DISPLAY 0.617021 (-1450 3560);
PAINT PINK (-1450 3560);
FORCEPROP 2 LAST CDS_LIB mstr_standard
J 2
(-1450 3550);
DISPLAY 0.787234 (-1450 3550);
PAINT MONO (-1450 3550);
DISPLAY INVISIBLE (-1450 3550);
FORCEPROP 1 LAST BODY_TYPE PLUMBING
J 0
(-1450 3500);
DISPLAY 1.234043 (-1450 3500);
PAINT GREEN (-1450 3500);
DISPLAY INVISIBLE (-1450 3500);
FORCEPROP 1 LAST HDL_TAP TRUE
J 0
(-1125 3425);
DISPLAY 1.234043 (-1125 3425);
PAINT GREEN (-1125 3425);
DISPLAY INVISIBLE (-1125 3425);
FORCEPROP 1 LAST PATH I51
J 0
(-1452 3550);
DISPLAY 0.872340 (-1452 3550);
PAINT GREEN (-1452 3550);
DISPLAY INVISIBLE (-1452 3550);
FORCEADD TAP..6
(-1450 3650);
FORCEPROP 3 LASTPIN (-1400 3650) SIG_NAME M_A_MA<3>
J 0
(-1390 3660);
DISPLAY 0.659574 (-1390 3660);
PAINT MONO (-1390 3660);
DISPLAY INVISIBLE (-1390 3660);
FORCEPROP 1 LASTPIN (-1400 3650) BN 3
J 0
(-1450 3660);
DISPLAY 0.617021 (-1450 3660);
PAINT PINK (-1450 3660);
FORCEPROP 2 LAST CDS_LIB mstr_standard
J 2
(-1450 3650);
DISPLAY 0.787234 (-1450 3650);
PAINT MONO (-1450 3650);
DISPLAY INVISIBLE (-1450 3650);
FORCEPROP 1 LAST BODY_TYPE PLUMBING
J 0
(-1450 3600);
DISPLAY 1.234043 (-1450 3600);
PAINT GREEN (-1450 3600);
DISPLAY INVISIBLE (-1450 3600);
FORCEPROP 1 LAST HDL_TAP TRUE
J 0
(-1125 3525);
DISPLAY 1.234043 (-1125 3525);
PAINT GREEN (-1125 3525);
DISPLAY INVISIBLE (-1125 3525);
FORCEPROP 1 LAST PATH I52
J 0
(-1452 3650);
DISPLAY 0.872340 (-1452 3650);
PAINT GREEN (-1452 3650);
DISPLAY INVISIBLE (-1452 3650);
FORCEADD TAP..6
(-1450 3750);
FORCEPROP 3 LASTPIN (-1400 3750) SIG_NAME M_A_MA<5>
J 0
(-1390 3760);
DISPLAY 0.659574 (-1390 3760);
PAINT MONO (-1390 3760);
DISPLAY INVISIBLE (-1390 3760);
FORCEPROP 1 LASTPIN (-1400 3750) BN 5
J 0
(-1450 3760);
DISPLAY 0.617021 (-1450 3760);
PAINT PINK (-1450 3760);
FORCEPROP 2 LAST CDS_LIB mstr_standard
J 2
(-1450 3750);
DISPLAY 0.787234 (-1450 3750);
PAINT MONO (-1450 3750);
DISPLAY INVISIBLE (-1450 3750);
FORCEPROP 1 LAST BODY_TYPE PLUMBING
J 0
(-1450 3700);
DISPLAY 1.234043 (-1450 3700);
PAINT GREEN (-1450 3700);
DISPLAY INVISIBLE (-1450 3700);
FORCEPROP 1 LAST HDL_TAP TRUE
J 0
(-1125 3625);
DISPLAY 1.234043 (-1125 3625);
PAINT GREEN (-1125 3625);
DISPLAY INVISIBLE (-1125 3625);
FORCEPROP 1 LAST PATH I53
J 0
(-1452 3750);
DISPLAY 0.872340 (-1452 3750);
PAINT GREEN (-1452 3750);
DISPLAY INVISIBLE (-1452 3750);
FORCEADD TAP..6
(-1450 3900);
FORCEPROP 3 LASTPIN (-1400 3900) SIG_NAME M_A_MA<8>
J 0
(-1390 3910);
DISPLAY 0.659574 (-1390 3910);
PAINT MONO (-1390 3910);
DISPLAY INVISIBLE (-1390 3910);
FORCEPROP 1 LASTPIN (-1400 3900) BN 8
J 0
(-1450 3910);
DISPLAY 0.617021 (-1450 3910);
PAINT PINK (-1450 3910);
FORCEPROP 2 LAST CDS_LIB mstr_standard
J 2
(-1450 3900);
DISPLAY 0.787234 (-1450 3900);
PAINT MONO (-1450 3900);
DISPLAY INVISIBLE (-1450 3900);
FORCEPROP 1 LAST BODY_TYPE PLUMBING
J 0
(-1450 3850);
DISPLAY 1.234043 (-1450 3850);
PAINT GREEN (-1450 3850);
DISPLAY INVISIBLE (-1450 3850);
FORCEPROP 1 LAST HDL_TAP TRUE
J 0
(-1125 3775);
DISPLAY 1.234043 (-1125 3775);
PAINT GREEN (-1125 3775);
DISPLAY INVISIBLE (-1125 3775);
FORCEPROP 1 LAST PATH I54
J 0
(-1452 3900);
DISPLAY 0.872340 (-1452 3900);
PAINT GREEN (-1452 3900);
DISPLAY INVISIBLE (-1452 3900);
FORCEADD TAP..6
(-1450 3800);
FORCEPROP 3 LASTPIN (-1400 3800) SIG_NAME M_A_MA<6>
J 0
(-1390 3810);
DISPLAY 0.659574 (-1390 3810);
PAINT MONO (-1390 3810);
DISPLAY INVISIBLE (-1390 3810);
FORCEPROP 1 LASTPIN (-1400 3800) BN 6
J 0
(-1450 3810);
DISPLAY 0.617021 (-1450 3810);
PAINT PINK (-1450 3810);
FORCEPROP 2 LAST CDS_LIB mstr_standard
J 2
(-1450 3800);
DISPLAY 0.787234 (-1450 3800);
PAINT MONO (-1450 3800);
DISPLAY INVISIBLE (-1450 3800);
FORCEPROP 1 LAST BODY_TYPE PLUMBING
J 0
(-1450 3750);
DISPLAY 1.234043 (-1450 3750);
PAINT GREEN (-1450 3750);
DISPLAY INVISIBLE (-1450 3750);
FORCEPROP 1 LAST HDL_TAP TRUE
J 0
(-1125 3675);
DISPLAY 1.234043 (-1125 3675);
PAINT GREEN (-1125 3675);
DISPLAY INVISIBLE (-1125 3675);
FORCEPROP 1 LAST PATH I55
J 0
(-1452 3800);
DISPLAY 0.872340 (-1452 3800);
PAINT GREEN (-1452 3800);
DISPLAY INVISIBLE (-1452 3800);
FORCEADD TAP..6
(-1450 3850);
FORCEPROP 3 LASTPIN (-1400 3850) SIG_NAME M_A_MA<7>
J 0
(-1390 3860);
DISPLAY 0.659574 (-1390 3860);
PAINT MONO (-1390 3860);
DISPLAY INVISIBLE (-1390 3860);
FORCEPROP 1 LASTPIN (-1400 3850) BN 7
J 0
(-1450 3860);
DISPLAY 0.617021 (-1450 3860);
PAINT PINK (-1450 3860);
FORCEPROP 2 LAST CDS_LIB mstr_standard
J 2
(-1450 3850);
DISPLAY 0.787234 (-1450 3850);
PAINT MONO (-1450 3850);
DISPLAY INVISIBLE (-1450 3850);
FORCEPROP 1 LAST BODY_TYPE PLUMBING
J 0
(-1450 3800);
DISPLAY 1.234043 (-1450 3800);
PAINT GREEN (-1450 3800);
DISPLAY INVISIBLE (-1450 3800);
FORCEPROP 1 LAST HDL_TAP TRUE
J 0
(-1125 3725);
DISPLAY 1.234043 (-1125 3725);
PAINT GREEN (-1125 3725);
DISPLAY INVISIBLE (-1125 3725);
FORCEPROP 1 LAST PATH I56
J 0
(-1452 3850);
DISPLAY 0.872340 (-1452 3850);
PAINT GREEN (-1452 3850);
DISPLAY INVISIBLE (-1452 3850);
FORCEADD TAP..6
(-1450 3950);
FORCEPROP 3 LASTPIN (-1400 3950) SIG_NAME M_A_MA<9>
J 0
(-1390 3960);
DISPLAY 0.659574 (-1390 3960);
PAINT MONO (-1390 3960);
DISPLAY INVISIBLE (-1390 3960);
FORCEPROP 1 LASTPIN (-1400 3950) BN 9
J 0
(-1450 3960);
DISPLAY 0.617021 (-1450 3960);
PAINT PINK (-1450 3960);
FORCEPROP 2 LAST CDS_LIB mstr_standard
J 2
(-1450 3950);
DISPLAY 0.787234 (-1450 3950);
PAINT MONO (-1450 3950);
DISPLAY INVISIBLE (-1450 3950);
FORCEPROP 1 LAST BODY_TYPE PLUMBING
J 0
(-1450 3900);
DISPLAY 1.234043 (-1450 3900);
PAINT GREEN (-1450 3900);
DISPLAY INVISIBLE (-1450 3900);
FORCEPROP 1 LAST HDL_TAP TRUE
J 0
(-1125 3825);
DISPLAY 1.234043 (-1125 3825);
PAINT GREEN (-1125 3825);
DISPLAY INVISIBLE (-1125 3825);
FORCEPROP 1 LAST PATH I57
J 0
(-1452 3950);
DISPLAY 0.872340 (-1452 3950);
PAINT GREEN (-1452 3950);
DISPLAY INVISIBLE (-1452 3950);
FORCEADD TAP..6
(-1450 4000);
FORCEPROP 3 LASTPIN (-1400 4000) SIG_NAME M_A_MA<10>
J 0
(-1390 4010);
DISPLAY 0.659574 (-1390 4010);
PAINT MONO (-1390 4010);
DISPLAY INVISIBLE (-1390 4010);
FORCEPROP 1 LASTPIN (-1400 4000) BN 10
J 0
(-1450 4010);
DISPLAY 0.617021 (-1450 4010);
PAINT PINK (-1450 4010);
FORCEPROP 2 LAST CDS_LIB mstr_standard
J 2
(-1450 4000);
DISPLAY 0.787234 (-1450 4000);
PAINT MONO (-1450 4000);
DISPLAY INVISIBLE (-1450 4000);
FORCEPROP 1 LAST BODY_TYPE PLUMBING
J 0
(-1450 3950);
DISPLAY 1.234043 (-1450 3950);
PAINT GREEN (-1450 3950);
DISPLAY INVISIBLE (-1450 3950);
FORCEPROP 1 LAST HDL_TAP TRUE
J 0
(-1125 3875);
DISPLAY 1.234043 (-1125 3875);
PAINT GREEN (-1125 3875);
DISPLAY INVISIBLE (-1125 3875);
FORCEPROP 1 LAST PATH I58
J 0
(-1452 4000);
DISPLAY 0.872340 (-1452 4000);
PAINT GREEN (-1452 4000);
DISPLAY INVISIBLE (-1452 4000);
FORCEADD TAP..6
R 2
(100 1200);
FORCEPROP 3 LASTPIN (50 1200) SIG_NAME M_A_DQ<0>
J 0
(60 1210);
DISPLAY 0.659574 (60 1210);
PAINT MONO (60 1210);
DISPLAY INVISIBLE (60 1210);
FORCEPROP 1 LASTPIN (50 1200) BN 0
J 2
(100 1210);
DISPLAY 0.617021 (100 1210);
PAINT PINK (100 1210);
FORCEPROP 2 LAST CDS_LIB mstr_standard
J 2
(100 1200);
DISPLAY 0.787234 (100 1200);
PAINT MONO (100 1200);
DISPLAY INVISIBLE (100 1200);
FORCEPROP 1 LAST BODY_TYPE PLUMBING
J 2
(100 1150);
DISPLAY 1.234043 (100 1150);
PAINT GREEN (100 1150);
DISPLAY INVISIBLE (100 1150);
FORCEPROP 1 LAST HDL_TAP TRUE
J 2
(-225 1075);
DISPLAY 1.234043 (-225 1075);
PAINT GREEN (-225 1075);
DISPLAY INVISIBLE (-225 1075);
FORCEPROP 1 LAST PATH I59
J 2
(102 1200);
DISPLAY 0.872340 (102 1200);
PAINT GREEN (102 1200);
DISPLAY INVISIBLE (102 1200);
FORCEADD OFFPAGE..1
(-2300 1650);
FORCEPROP 2 LAST $XR0 23 
J 0
(-2581 1650);
DISPLAY 0.638298 (-2581 1650);
PAINT MONO (-2581 1650);
FORCEPROP 2 LAST $XR1 43 
J 0
(-2671 1650);
DISPLAY 0.638298 (-2671 1650);
PAINT MONO (-2671 1650);
FORCEPROP 2 LAST CDS_LIB mstr_standard
J 0
(-2300 1650);
DISPLAY 0.787234 (-2300 1650);
PAINT MONO (-2300 1650);
DISPLAY INVISIBLE (-2300 1650);
FORCEPROP 1 LAST OFFPAGE TRUE
J 0
(-1975 1525);
DISPLAY 0.936170 (-1975 1525);
PAINT GREEN (-1975 1525);
DISPLAY INVISIBLE (-1975 1525);
FORCEPROP 1 LAST COMMENT_BODY TRUE
J 0
(-2175 1550);
DISPLAY 0.936170 (-2175 1550);
PAINT GREEN (-2175 1550);
DISPLAY INVISIBLE (-2175 1550);
FORCEPROP 2 LAST PATH I6
J 0
(-2575 1700);
DISPLAY 1.021277 (-2575 1700);
PAINT ORANGE (-2575 1700);
DISPLAY INVISIBLE (-2575 1700);
FORCEADD TAP..6
R 2
(100 1300);
FORCEPROP 3 LASTPIN (50 1300) SIG_NAME M_A_DQ<2>
J 0
(60 1310);
DISPLAY 0.659574 (60 1310);
PAINT MONO (60 1310);
DISPLAY INVISIBLE (60 1310);
FORCEPROP 1 LASTPIN (50 1300) BN 2
J 2
(100 1310);
DISPLAY 0.617021 (100 1310);
PAINT PINK (100 1310);
FORCEPROP 2 LAST CDS_LIB mstr_standard
J 2
(100 1300);
DISPLAY 0.787234 (100 1300);
PAINT MONO (100 1300);
DISPLAY INVISIBLE (100 1300);
FORCEPROP 1 LAST BODY_TYPE PLUMBING
J 2
(100 1250);
DISPLAY 1.234043 (100 1250);
PAINT GREEN (100 1250);
DISPLAY INVISIBLE (100 1250);
FORCEPROP 1 LAST HDL_TAP TRUE
J 2
(-225 1175);
DISPLAY 1.234043 (-225 1175);
PAINT GREEN (-225 1175);
DISPLAY INVISIBLE (-225 1175);
FORCEPROP 1 LAST PATH I60
J 2
(102 1300);
DISPLAY 0.872340 (102 1300);
PAINT GREEN (102 1300);
DISPLAY INVISIBLE (102 1300);
FORCEADD TAP..6
R 2
(100 1250);
FORCEPROP 3 LASTPIN (50 1250) SIG_NAME M_A_DQ<1>
J 0
(60 1260);
DISPLAY 0.659574 (60 1260);
PAINT MONO (60 1260);
DISPLAY INVISIBLE (60 1260);
FORCEPROP 1 LASTPIN (50 1250) BN 1
J 2
(100 1260);
DISPLAY 0.617021 (100 1260);
PAINT PINK (100 1260);
FORCEPROP 2 LAST CDS_LIB mstr_standard
J 2
(100 1250);
DISPLAY 0.787234 (100 1250);
PAINT MONO (100 1250);
DISPLAY INVISIBLE (100 1250);
FORCEPROP 1 LAST BODY_TYPE PLUMBING
J 2
(100 1200);
DISPLAY 1.234043 (100 1200);
PAINT GREEN (100 1200);
DISPLAY INVISIBLE (100 1200);
FORCEPROP 1 LAST HDL_TAP TRUE
J 2
(-225 1125);
DISPLAY 1.234043 (-225 1125);
PAINT GREEN (-225 1125);
DISPLAY INVISIBLE (-225 1125);
FORCEPROP 1 LAST PATH I61
J 2
(102 1250);
DISPLAY 0.872340 (102 1250);
PAINT GREEN (102 1250);
DISPLAY INVISIBLE (102 1250);
FORCEADD TAP..6
R 2
(100 1350);
FORCEPROP 3 LASTPIN (50 1350) SIG_NAME M_A_DQ<3>
J 0
(60 1360);
DISPLAY 0.659574 (60 1360);
PAINT MONO (60 1360);
DISPLAY INVISIBLE (60 1360);
FORCEPROP 1 LASTPIN (50 1350) BN 3
J 2
(100 1360);
DISPLAY 0.617021 (100 1360);
PAINT PINK (100 1360);
FORCEPROP 2 LAST CDS_LIB mstr_standard
J 2
(100 1350);
DISPLAY 0.787234 (100 1350);
PAINT MONO (100 1350);
DISPLAY INVISIBLE (100 1350);
FORCEPROP 1 LAST BODY_TYPE PLUMBING
J 2
(100 1300);
DISPLAY 1.234043 (100 1300);
PAINT GREEN (100 1300);
DISPLAY INVISIBLE (100 1300);
FORCEPROP 1 LAST HDL_TAP TRUE
J 2
(-225 1225);
DISPLAY 1.234043 (-225 1225);
PAINT GREEN (-225 1225);
DISPLAY INVISIBLE (-225 1225);
FORCEPROP 1 LAST PATH I62
J 2
(102 1350);
DISPLAY 0.872340 (102 1350);
PAINT GREEN (102 1350);
DISPLAY INVISIBLE (102 1350);
FORCEADD TAP..6
R 2
(100 1450);
FORCEPROP 3 LASTPIN (50 1450) SIG_NAME M_A_DQ<5>
J 0
(60 1460);
DISPLAY 0.659574 (60 1460);
PAINT MONO (60 1460);
DISPLAY INVISIBLE (60 1460);
FORCEPROP 1 LASTPIN (50 1450) BN 5
J 2
(100 1460);
DISPLAY 0.617021 (100 1460);
PAINT PINK (100 1460);
FORCEPROP 2 LAST CDS_LIB mstr_standard
J 2
(100 1450);
DISPLAY 0.787234 (100 1450);
PAINT MONO (100 1450);
DISPLAY INVISIBLE (100 1450);
FORCEPROP 1 LAST BODY_TYPE PLUMBING
J 2
(100 1400);
DISPLAY 1.234043 (100 1400);
PAINT GREEN (100 1400);
DISPLAY INVISIBLE (100 1400);
FORCEPROP 1 LAST HDL_TAP TRUE
J 2
(-225 1325);
DISPLAY 1.234043 (-225 1325);
PAINT GREEN (-225 1325);
DISPLAY INVISIBLE (-225 1325);
FORCEPROP 1 LAST PATH I63
J 2
(102 1450);
DISPLAY 0.872340 (102 1450);
PAINT GREEN (102 1450);
DISPLAY INVISIBLE (102 1450);
FORCEADD TAP..6
R 2
(100 1400);
FORCEPROP 3 LASTPIN (50 1400) SIG_NAME M_A_DQ<4>
J 0
(60 1410);
DISPLAY 0.659574 (60 1410);
PAINT MONO (60 1410);
DISPLAY INVISIBLE (60 1410);
FORCEPROP 1 LASTPIN (50 1400) BN 4
J 2
(100 1410);
DISPLAY 0.617021 (100 1410);
PAINT PINK (100 1410);
FORCEPROP 2 LAST CDS_LIB mstr_standard
J 2
(100 1400);
DISPLAY 0.787234 (100 1400);
PAINT MONO (100 1400);
DISPLAY INVISIBLE (100 1400);
FORCEPROP 1 LAST BODY_TYPE PLUMBING
J 2
(100 1350);
DISPLAY 1.234043 (100 1350);
PAINT GREEN (100 1350);
DISPLAY INVISIBLE (100 1350);
FORCEPROP 1 LAST HDL_TAP TRUE
J 2
(-225 1275);
DISPLAY 1.234043 (-225 1275);
PAINT GREEN (-225 1275);
DISPLAY INVISIBLE (-225 1275);
FORCEPROP 1 LAST PATH I64
J 2
(102 1400);
DISPLAY 0.872340 (102 1400);
PAINT GREEN (102 1400);
DISPLAY INVISIBLE (102 1400);
FORCEADD TAP..6
R 2
(100 1600);
FORCEPROP 3 LASTPIN (50 1600) SIG_NAME M_A_DQ<8>
J 0
(60 1610);
DISPLAY 0.659574 (60 1610);
PAINT MONO (60 1610);
DISPLAY INVISIBLE (60 1610);
FORCEPROP 1 LASTPIN (50 1600) BN 8
J 2
(100 1610);
DISPLAY 0.617021 (100 1610);
PAINT PINK (100 1610);
FORCEPROP 2 LAST CDS_LIB mstr_standard
J 2
(100 1600);
DISPLAY 0.787234 (100 1600);
PAINT MONO (100 1600);
DISPLAY INVISIBLE (100 1600);
FORCEPROP 1 LAST BODY_TYPE PLUMBING
J 2
(100 1550);
DISPLAY 1.234043 (100 1550);
PAINT GREEN (100 1550);
DISPLAY INVISIBLE (100 1550);
FORCEPROP 1 LAST HDL_TAP TRUE
J 2
(-225 1475);
DISPLAY 1.234043 (-225 1475);
PAINT GREEN (-225 1475);
DISPLAY INVISIBLE (-225 1475);
FORCEPROP 1 LAST PATH I65
J 2
(102 1600);
DISPLAY 0.872340 (102 1600);
PAINT GREEN (102 1600);
DISPLAY INVISIBLE (102 1600);
FORCEADD TAP..6
R 2
(100 1550);
FORCEPROP 3 LASTPIN (50 1550) SIG_NAME M_A_DQ<7>
J 0
(60 1560);
DISPLAY 0.659574 (60 1560);
PAINT MONO (60 1560);
DISPLAY INVISIBLE (60 1560);
FORCEPROP 1 LASTPIN (50 1550) BN 7
J 2
(100 1560);
DISPLAY 0.617021 (100 1560);
PAINT PINK (100 1560);
FORCEPROP 2 LAST CDS_LIB mstr_standard
J 2
(100 1550);
DISPLAY 0.787234 (100 1550);
PAINT MONO (100 1550);
DISPLAY INVISIBLE (100 1550);
FORCEPROP 1 LAST BODY_TYPE PLUMBING
J 2
(100 1500);
DISPLAY 1.234043 (100 1500);
PAINT GREEN (100 1500);
DISPLAY INVISIBLE (100 1500);
FORCEPROP 1 LAST HDL_TAP TRUE
J 2
(-225 1425);
DISPLAY 1.234043 (-225 1425);
PAINT GREEN (-225 1425);
DISPLAY INVISIBLE (-225 1425);
FORCEPROP 1 LAST PATH I66
J 2
(102 1550);
DISPLAY 0.872340 (102 1550);
PAINT GREEN (102 1550);
DISPLAY INVISIBLE (102 1550);
FORCEADD TAP..6
R 2
(100 1500);
FORCEPROP 3 LASTPIN (50 1500) SIG_NAME M_A_DQ<6>
J 0
(60 1510);
DISPLAY 0.659574 (60 1510);
PAINT MONO (60 1510);
DISPLAY INVISIBLE (60 1510);
FORCEPROP 1 LASTPIN (50 1500) BN 6
J 2
(100 1510);
DISPLAY 0.617021 (100 1510);
PAINT PINK (100 1510);
FORCEPROP 2 LAST CDS_LIB mstr_standard
J 2
(100 1500);
DISPLAY 0.787234 (100 1500);
PAINT MONO (100 1500);
DISPLAY INVISIBLE (100 1500);
FORCEPROP 1 LAST BODY_TYPE PLUMBING
J 2
(100 1450);
DISPLAY 1.234043 (100 1450);
PAINT GREEN (100 1450);
DISPLAY INVISIBLE (100 1450);
FORCEPROP 1 LAST HDL_TAP TRUE
J 2
(-225 1375);
DISPLAY 1.234043 (-225 1375);
PAINT GREEN (-225 1375);
DISPLAY INVISIBLE (-225 1375);
FORCEPROP 1 LAST PATH I67
J 2
(102 1500);
DISPLAY 0.872340 (102 1500);
PAINT GREEN (102 1500);
DISPLAY INVISIBLE (102 1500);
FORCEADD TAP..6
R 2
(100 1650);
FORCEPROP 3 LASTPIN (50 1650) SIG_NAME M_A_DQ<9>
J 0
(60 1660);
DISPLAY 0.659574 (60 1660);
PAINT MONO (60 1660);
DISPLAY INVISIBLE (60 1660);
FORCEPROP 1 LASTPIN (50 1650) BN 9
J 2
(100 1660);
DISPLAY 0.617021 (100 1660);
PAINT PINK (100 1660);
FORCEPROP 2 LAST CDS_LIB mstr_standard
J 2
(100 1650);
DISPLAY 0.787234 (100 1650);
PAINT MONO (100 1650);
DISPLAY INVISIBLE (100 1650);
FORCEPROP 1 LAST BODY_TYPE PLUMBING
J 2
(100 1600);
DISPLAY 1.234043 (100 1600);
PAINT GREEN (100 1600);
DISPLAY INVISIBLE (100 1600);
FORCEPROP 1 LAST HDL_TAP TRUE
J 2
(-225 1525);
DISPLAY 1.234043 (-225 1525);
PAINT GREEN (-225 1525);
DISPLAY INVISIBLE (-225 1525);
FORCEPROP 1 LAST PATH I68
J 2
(102 1650);
DISPLAY 0.872340 (102 1650);
PAINT GREEN (102 1650);
DISPLAY INVISIBLE (102 1650);
FORCEADD TAP..6
R 2
(100 1700);
FORCEPROP 3 LASTPIN (50 1700) SIG_NAME M_A_DQ<10>
J 0
(60 1710);
DISPLAY 0.659574 (60 1710);
PAINT MONO (60 1710);
DISPLAY INVISIBLE (60 1710);
FORCEPROP 1 LASTPIN (50 1700) BN 10
J 2
(100 1710);
DISPLAY 0.617021 (100 1710);
PAINT PINK (100 1710);
FORCEPROP 2 LAST CDS_LIB mstr_standard
J 2
(100 1700);
DISPLAY 0.787234 (100 1700);
PAINT MONO (100 1700);
DISPLAY INVISIBLE (100 1700);
FORCEPROP 1 LAST BODY_TYPE PLUMBING
J 2
(100 1650);
DISPLAY 1.234043 (100 1650);
PAINT GREEN (100 1650);
DISPLAY INVISIBLE (100 1650);
FORCEPROP 1 LAST HDL_TAP TRUE
J 2
(-225 1575);
DISPLAY 1.234043 (-225 1575);
PAINT GREEN (-225 1575);
DISPLAY INVISIBLE (-225 1575);
FORCEPROP 1 LAST PATH I69
J 2
(102 1700);
DISPLAY 0.872340 (102 1700);
PAINT GREEN (102 1700);
DISPLAY INVISIBLE (102 1700);
FORCEADD OFFPAGE..5
(-2325 1700);
FORCEPROP 2 LAST $XR0 43 
J 0
(-2579 1700);
DISPLAY 0.638298 (-2579 1700);
PAINT MONO (-2579 1700);
FORCEPROP 2 LAST $XR1 23 
J 0
(-2669 1700);
DISPLAY 0.638298 (-2669 1700);
PAINT MONO (-2669 1700);
FORCEPROP 2 LAST CDS_LIB mstr_standard
J 0
(-2325 1700);
DISPLAY 0.787234 (-2325 1700);
PAINT MONO (-2325 1700);
DISPLAY INVISIBLE (-2325 1700);
FORCEPROP 1 LAST OFFPAGE TRUE
J 0
(-2000 1575);
DISPLAY 1.404255 (-2000 1575);
PAINT GREEN (-2000 1575);
DISPLAY INVISIBLE (-2000 1575);
FORCEPROP 1 LAST COMMENT_BODY TRUE
J 0
(-2225 1625);
DISPLAY 1.404255 (-2225 1625);
PAINT GREEN (-2225 1625);
DISPLAY INVISIBLE (-2225 1625);
FORCEPROP 2 LAST PATH I7
J 0
(-2575 1750);
DISPLAY 1.021277 (-2575 1750);
PAINT ORANGE (-2575 1750);
DISPLAY INVISIBLE (-2575 1750);
FORCEADD TAP..6
R 2
(100 1800);
FORCEPROP 3 LASTPIN (50 1800) SIG_NAME M_A_DQ<12>
J 0
(60 1810);
DISPLAY 0.659574 (60 1810);
PAINT MONO (60 1810);
DISPLAY INVISIBLE (60 1810);
FORCEPROP 1 LASTPIN (50 1800) BN 12
J 2
(100 1810);
DISPLAY 0.617021 (100 1810);
PAINT PINK (100 1810);
FORCEPROP 2 LAST CDS_LIB mstr_standard
J 2
(100 1800);
DISPLAY 0.787234 (100 1800);
PAINT MONO (100 1800);
DISPLAY INVISIBLE (100 1800);
FORCEPROP 1 LAST BODY_TYPE PLUMBING
J 2
(100 1750);
DISPLAY 1.234043 (100 1750);
PAINT GREEN (100 1750);
DISPLAY INVISIBLE (100 1750);
FORCEPROP 1 LAST HDL_TAP TRUE
J 2
(-225 1675);
DISPLAY 1.234043 (-225 1675);
PAINT GREEN (-225 1675);
DISPLAY INVISIBLE (-225 1675);
FORCEPROP 1 LAST PATH I70
J 2
(102 1800);
DISPLAY 0.872340 (102 1800);
PAINT GREEN (102 1800);
DISPLAY INVISIBLE (102 1800);
FORCEADD TAP..6
R 2
(100 1750);
FORCEPROP 3 LASTPIN (50 1750) SIG_NAME M_A_DQ<11>
J 0
(60 1760);
DISPLAY 0.659574 (60 1760);
PAINT MONO (60 1760);
DISPLAY INVISIBLE (60 1760);
FORCEPROP 1 LASTPIN (50 1750) BN 11
J 2
(100 1760);
DISPLAY 0.617021 (100 1760);
PAINT PINK (100 1760);
FORCEPROP 2 LAST CDS_LIB mstr_standard
J 2
(100 1750);
DISPLAY 0.787234 (100 1750);
PAINT MONO (100 1750);
DISPLAY INVISIBLE (100 1750);
FORCEPROP 1 LAST BODY_TYPE PLUMBING
J 2
(100 1700);
DISPLAY 1.234043 (100 1700);
PAINT GREEN (100 1700);
DISPLAY INVISIBLE (100 1700);
FORCEPROP 1 LAST HDL_TAP TRUE
J 2
(-225 1625);
DISPLAY 1.234043 (-225 1625);
PAINT GREEN (-225 1625);
DISPLAY INVISIBLE (-225 1625);
FORCEPROP 1 LAST PATH I71
J 2
(102 1750);
DISPLAY 0.872340 (102 1750);
PAINT GREEN (102 1750);
DISPLAY INVISIBLE (102 1750);
FORCEADD TAP..6
R 2
(100 1850);
FORCEPROP 3 LASTPIN (50 1850) SIG_NAME M_A_DQ<13>
J 0
(60 1860);
DISPLAY 0.659574 (60 1860);
PAINT MONO (60 1860);
DISPLAY INVISIBLE (60 1860);
FORCEPROP 1 LASTPIN (50 1850) BN 13
J 2
(100 1860);
DISPLAY 0.617021 (100 1860);
PAINT PINK (100 1860);
FORCEPROP 2 LAST CDS_LIB mstr_standard
J 2
(100 1850);
DISPLAY 0.787234 (100 1850);
PAINT MONO (100 1850);
DISPLAY INVISIBLE (100 1850);
FORCEPROP 1 LAST BODY_TYPE PLUMBING
J 2
(100 1800);
DISPLAY 1.234043 (100 1800);
PAINT GREEN (100 1800);
DISPLAY INVISIBLE (100 1800);
FORCEPROP 1 LAST HDL_TAP TRUE
J 2
(-225 1725);
DISPLAY 1.234043 (-225 1725);
PAINT GREEN (-225 1725);
DISPLAY INVISIBLE (-225 1725);
FORCEPROP 1 LAST PATH I72
J 2
(102 1850);
DISPLAY 0.872340 (102 1850);
PAINT GREEN (102 1850);
DISPLAY INVISIBLE (102 1850);
FORCEADD TAP..6
R 2
(100 1950);
FORCEPROP 3 LASTPIN (50 1950) SIG_NAME M_A_DQ<15>
J 0
(60 1960);
DISPLAY 0.659574 (60 1960);
PAINT MONO (60 1960);
DISPLAY INVISIBLE (60 1960);
FORCEPROP 1 LASTPIN (50 1950) BN 15
J 2
(100 1960);
DISPLAY 0.617021 (100 1960);
PAINT PINK (100 1960);
FORCEPROP 2 LAST CDS_LIB mstr_standard
J 2
(100 1950);
DISPLAY 0.787234 (100 1950);
PAINT MONO (100 1950);
DISPLAY INVISIBLE (100 1950);
FORCEPROP 1 LAST BODY_TYPE PLUMBING
J 2
(100 1900);
DISPLAY 1.234043 (100 1900);
PAINT GREEN (100 1900);
DISPLAY INVISIBLE (100 1900);
FORCEPROP 1 LAST HDL_TAP TRUE
J 2
(-225 1825);
DISPLAY 1.234043 (-225 1825);
PAINT GREEN (-225 1825);
DISPLAY INVISIBLE (-225 1825);
FORCEPROP 1 LAST PATH I73
J 2
(102 1950);
DISPLAY 0.872340 (102 1950);
PAINT GREEN (102 1950);
DISPLAY INVISIBLE (102 1950);
FORCEADD TAP..6
R 2
(100 1900);
FORCEPROP 3 LASTPIN (50 1900) SIG_NAME M_A_DQ<14>
J 0
(60 1910);
DISPLAY 0.659574 (60 1910);
PAINT MONO (60 1910);
DISPLAY INVISIBLE (60 1910);
FORCEPROP 1 LASTPIN (50 1900) BN 14
J 2
(100 1910);
DISPLAY 0.617021 (100 1910);
PAINT PINK (100 1910);
FORCEPROP 2 LAST CDS_LIB mstr_standard
J 2
(100 1900);
DISPLAY 0.787234 (100 1900);
PAINT MONO (100 1900);
DISPLAY INVISIBLE (100 1900);
FORCEPROP 1 LAST BODY_TYPE PLUMBING
J 2
(100 1850);
DISPLAY 1.234043 (100 1850);
PAINT GREEN (100 1850);
DISPLAY INVISIBLE (100 1850);
FORCEPROP 1 LAST HDL_TAP TRUE
J 2
(-225 1775);
DISPLAY 1.234043 (-225 1775);
PAINT GREEN (-225 1775);
DISPLAY INVISIBLE (-225 1775);
FORCEPROP 1 LAST PATH I74
J 2
(102 1900);
DISPLAY 0.872340 (102 1900);
PAINT GREEN (102 1900);
DISPLAY INVISIBLE (102 1900);
FORCEADD SCONN288_H44441003..4
(1600 1650);
FORCEPROP 1 LAST LOCATION J6T1
J 0
(1150 2750);
DISPLAY 0.617021 (1150 2750);
PAINT AQUA (1150 2750);
FORCEPROP 1 LAST PART_NUMBER H44441-003
J 0
(1150 600);
DISPLAY 0.617021 (1150 600);
PAINT BLUE (1150 600);
FORCEPROP 1 LAST MATERIAL SCONN
J 0
(1150 2700);
DISPLAY 0.617021 (1150 2700);
PAINT SKYBLUE (1150 2700);
FORCEPROP 2 LASTPIN (1100 2200) $PN 77
J 2
(1090 2210);
DISPLAY 0.617021 (1090 2210);
PAINT ORANGE (1090 2210);
FORCEPROP 2 LASTPIN (1100 2150) $PN 221
J 2
(1090 2160);
DISPLAY 0.617021 (1090 2160);
PAINT ORANGE (1090 2160);
FORCEPROP 2 LASTPIN (1100 2500) $PN 142
J 2
(1090 2510);
DISPLAY 0.617021 (1090 2510);
PAINT ORANGE (1090 2510);
FORCEPROP 2 LASTPIN (1100 2450) $PN 143
J 2
(1090 2460);
DISPLAY 0.617021 (1090 2460);
PAINT ORANGE (1090 2460);
FORCEPROP 2 LASTPIN (1100 2400) $PN 288
J 2
(1090 2410);
DISPLAY 0.617021 (1090 2410);
PAINT ORANGE (1090 2410);
FORCEPROP 2 LASTPIN (1100 2350) $PN 286
J 2
(1090 2360);
DISPLAY 0.617021 (1090 2360);
PAINT ORANGE (1090 2360);
FORCEPROP 2 LASTPIN (1100 2300) $PN 287
J 2
(1090 2310);
DISPLAY 0.617021 (1090 2310);
PAINT ORANGE (1090 2310);
FORCEPROP 2 LASTPIN (1100 2050) $PN 59
J 2
(1090 2060);
DISPLAY 0.617021 (1090 2060);
PAINT ORANGE (1090 2060);
FORCEPROP 2 LASTPIN (1100 2000) $PN 61
J 2
(1090 2010);
DISPLAY 0.617021 (1090 2010);
PAINT ORANGE (1090 2010);
FORCEPROP 2 LASTPIN (1100 1950) $PN 64
J 2
(1090 1960);
DISPLAY 0.617021 (1090 1960);
PAINT ORANGE (1090 1960);
FORCEPROP 2 LASTPIN (1100 1900) $PN 67
J 2
(1090 1910);
DISPLAY 0.617021 (1090 1910);
PAINT ORANGE (1090 1910);
FORCEPROP 2 LASTPIN (1100 1850) $PN 70
J 2
(1090 1860);
DISPLAY 0.617021 (1090 1860);
PAINT ORANGE (1090 1860);
FORCEPROP 2 LASTPIN (1100 1800) $PN 73
J 2
(1090 1810);
DISPLAY 0.617021 (1090 1810);
PAINT ORANGE (1090 1810);
FORCEPROP 2 LASTPIN (1100 1750) $PN 76
J 2
(1090 1760);
DISPLAY 0.617021 (1090 1760);
PAINT ORANGE (1090 1760);
FORCEPROP 2 LASTPIN (1100 1700) $PN 80
J 2
(1090 1710);
DISPLAY 0.617021 (1090 1710);
PAINT ORANGE (1090 1710);
FORCEPROP 2 LASTPIN (1100 1650) $PN 83
J 2
(1090 1660);
DISPLAY 0.617021 (1090 1660);
PAINT ORANGE (1090 1660);
FORCEPROP 2 LASTPIN (1100 1600) $PN 85
J 2
(1090 1610);
DISPLAY 0.617021 (1090 1610);
PAINT ORANGE (1090 1610);
FORCEPROP 2 LASTPIN (1100 1550) $PN 88
J 2
(1090 1560);
DISPLAY 0.617021 (1090 1560);
PAINT ORANGE (1090 1560);
FORCEPROP 2 LASTPIN (1100 1500) $PN 90
J 2
(1090 1510);
DISPLAY 0.617021 (1090 1510);
PAINT ORANGE (1090 1510);
FORCEPROP 2 LASTPIN (1100 1450) $PN 92
J 2
(1090 1460);
DISPLAY 0.617021 (1090 1460);
PAINT ORANGE (1090 1460);
FORCEPROP 2 LASTPIN (1100 1400) $PN 204
J 2
(1090 1410);
DISPLAY 0.617021 (1090 1410);
PAINT ORANGE (1090 1410);
FORCEPROP 2 LASTPIN (1100 1350) $PN 206
J 2
(1090 1360);
DISPLAY 0.617021 (1090 1360);
PAINT ORANGE (1090 1360);
FORCEPROP 2 LASTPIN (1100 1300) $PN 209
J 2
(1090 1310);
DISPLAY 0.617021 (1090 1310);
PAINT ORANGE (1090 1310);
FORCEPROP 2 LASTPIN (1100 1250) $PN 212
J 2
(1090 1260);
DISPLAY 0.617021 (1090 1260);
PAINT ORANGE (1090 1260);
FORCEPROP 2 LASTPIN (1100 1200) $PN 215
J 2
(1090 1210);
DISPLAY 0.617021 (1090 1210);
PAINT ORANGE (1090 1210);
FORCEPROP 2 LASTPIN (1100 1150) $PN 217
J 2
(1090 1160);
DISPLAY 0.617021 (1090 1160);
PAINT ORANGE (1090 1160);
FORCEPROP 2 LASTPIN (1100 1100) $PN 220
J 2
(1090 1110);
DISPLAY 0.617021 (1090 1110);
PAINT ORANGE (1090 1110);
FORCEPROP 2 LASTPIN (1100 1050) $PN 223
J 2
(1090 1060);
DISPLAY 0.617021 (1090 1060);
PAINT ORANGE (1090 1060);
FORCEPROP 2 LASTPIN (1100 1000) $PN 226
J 2
(1090 1010);
DISPLAY 0.617021 (1090 1010);
PAINT ORANGE (1090 1010);
FORCEPROP 2 LASTPIN (1100 950) $PN 229
J 2
(1090 960);
DISPLAY 0.617021 (1090 960);
PAINT ORANGE (1090 960);
FORCEPROP 2 LASTPIN (1100 900) $PN 231
J 2
(1090 910);
DISPLAY 0.617021 (1090 910);
PAINT ORANGE (1090 910);
FORCEPROP 2 LASTPIN (1100 850) $PN 233
J 2
(1090 860);
DISPLAY 0.617021 (1090 860);
PAINT ORANGE (1090 860);
FORCEPROP 2 LASTPIN (1100 800) $PN 236
J 2
(1090 810);
DISPLAY 0.617021 (1090 810);
PAINT ORANGE (1090 810);
FORCEPROP 2 LASTPIN (2100 2500) $PN 1
J 0
(2110 2510);
DISPLAY 0.617021 (2110 2510);
PAINT ORANGE (2110 2510);
FORCEPROP 2 LASTPIN (2100 2450) $PN 145
J 0
(2110 2460);
DISPLAY 0.617021 (2110 2460);
PAINT ORANGE (2110 2460);
FORCEPROP 1 LAST PACK_TYPE PIP
J 0
(1150 2800);
PAINT SKYBLUE (1150 2800);
DISPLAY INVISIBLE (1150 2800);
FORCEPROP 2 LAST BOM_COST MEM
J 0
(1600 1650);
PAINT ORANGE (1600 1650);
DISPLAY INVISIBLE (1600 1650);
FORCEPROP 2 LAST CDS_LIB mstr_sconn
J 0
(1600 1650);
PAINT ORANGE (1600 1650);
DISPLAY INVISIBLE (1600 1650);
FORCEPROP 2 LAST SEC_TYPE PIP
J 0
(1150 2800);
DISPLAY 1.021277 (1150 2800);
PAINT ORANGE (1150 2800);
DISPLAY INVISIBLE (1150 2800);
FORCEPROP 2 LAST SEC 4
J 0
(1150 2800);
DISPLAY 0.680851 (1150 2800);
PAINT MONO (1150 2800);
DISPLAY INVISIBLE (1150 2800);
FORCEPROP 2 LAST CDS_LOCATION J6T1
J 0
(1150 2750);
DISPLAY 0.617021 (1150 2750);
PAINT AQUA (1150 2750);
DISPLAY INVISIBLE (1150 2750);
FORCEPROP 1 LAST PATH I75
J 0
(1600 2700);
PAINT GREEN (1600 2700);
DISPLAY INVISIBLE (1600 2700);
FORCEPROP 2 LAST ROOM DDR4_CH_A
J 0
(1600 1650);
PAINT ORANGE (1600 1650);
DISPLAY INVISIBLE (1600 1650);
FORCEADD TAP..6
R 2
(100 2000);
FORCEPROP 3 LASTPIN (50 2000) SIG_NAME M_A_DQ<16>
J 0
(60 2010);
DISPLAY 0.659574 (60 2010);
PAINT MONO (60 2010);
DISPLAY INVISIBLE (60 2010);
FORCEPROP 1 LASTPIN (50 2000) BN 16
J 2
(100 2010);
DISPLAY 0.617021 (100 2010);
PAINT PINK (100 2010);
FORCEPROP 2 LAST CDS_LIB mstr_standard
J 2
(100 2000);
DISPLAY 0.787234 (100 2000);
PAINT MONO (100 2000);
DISPLAY INVISIBLE (100 2000);
FORCEPROP 1 LAST BODY_TYPE PLUMBING
J 2
(100 1950);
DISPLAY 1.234043 (100 1950);
PAINT GREEN (100 1950);
DISPLAY INVISIBLE (100 1950);
FORCEPROP 1 LAST HDL_TAP TRUE
J 2
(-225 1875);
DISPLAY 1.234043 (-225 1875);
PAINT GREEN (-225 1875);
DISPLAY INVISIBLE (-225 1875);
FORCEPROP 1 LAST PATH I76
J 2
(102 2000);
DISPLAY 0.872340 (102 2000);
PAINT GREEN (102 2000);
DISPLAY INVISIBLE (102 2000);
FORCEADD TAP..6
R 2
(100 2050);
FORCEPROP 3 LASTPIN (50 2050) SIG_NAME M_A_DQ<17>
J 0
(60 2060);
DISPLAY 0.659574 (60 2060);
PAINT MONO (60 2060);
DISPLAY INVISIBLE (60 2060);
FORCEPROP 1 LASTPIN (50 2050) BN 17
J 2
(100 2060);
DISPLAY 0.617021 (100 2060);
PAINT PINK (100 2060);
FORCEPROP 2 LAST CDS_LIB mstr_standard
J 2
(100 2050);
DISPLAY 0.787234 (100 2050);
PAINT MONO (100 2050);
DISPLAY INVISIBLE (100 2050);
FORCEPROP 1 LAST BODY_TYPE PLUMBING
J 2
(100 2000);
DISPLAY 1.234043 (100 2000);
PAINT GREEN (100 2000);
DISPLAY INVISIBLE (100 2000);
FORCEPROP 1 LAST HDL_TAP TRUE
J 2
(-225 1925);
DISPLAY 1.234043 (-225 1925);
PAINT GREEN (-225 1925);
DISPLAY INVISIBLE (-225 1925);
FORCEPROP 1 LAST PATH I77
J 2
(102 2050);
DISPLAY 0.872340 (102 2050);
PAINT GREEN (102 2050);
DISPLAY INVISIBLE (102 2050);
FORCEADD TAP..6
R 2
(100 2100);
FORCEPROP 3 LASTPIN (50 2100) SIG_NAME M_A_DQ<18>
J 0
(60 2110);
DISPLAY 0.659574 (60 2110);
PAINT MONO (60 2110);
DISPLAY INVISIBLE (60 2110);
FORCEPROP 1 LASTPIN (50 2100) BN 18
J 2
(100 2110);
DISPLAY 0.617021 (100 2110);
PAINT PINK (100 2110);
FORCEPROP 2 LAST CDS_LIB mstr_standard
J 2
(100 2100);
DISPLAY 0.787234 (100 2100);
PAINT MONO (100 2100);
DISPLAY INVISIBLE (100 2100);
FORCEPROP 1 LAST BODY_TYPE PLUMBING
J 2
(100 2050);
DISPLAY 1.234043 (100 2050);
PAINT GREEN (100 2050);
DISPLAY INVISIBLE (100 2050);
FORCEPROP 1 LAST HDL_TAP TRUE
J 2
(-225 1975);
DISPLAY 1.234043 (-225 1975);
PAINT GREEN (-225 1975);
DISPLAY INVISIBLE (-225 1975);
FORCEPROP 1 LAST PATH I78
J 2
(102 2100);
DISPLAY 0.872340 (102 2100);
PAINT GREEN (102 2100);
DISPLAY INVISIBLE (102 2100);
FORCEADD TAP..6
R 2
(100 2150);
FORCEPROP 3 LASTPIN (50 2150) SIG_NAME M_A_DQ<19>
J 0
(60 2160);
DISPLAY 0.659574 (60 2160);
PAINT MONO (60 2160);
DISPLAY INVISIBLE (60 2160);
FORCEPROP 1 LASTPIN (50 2150) BN 19
J 2
(100 2160);
DISPLAY 0.617021 (100 2160);
PAINT PINK (100 2160);
FORCEPROP 2 LAST CDS_LIB mstr_standard
J 2
(100 2150);
DISPLAY 0.787234 (100 2150);
PAINT MONO (100 2150);
DISPLAY INVISIBLE (100 2150);
FORCEPROP 1 LAST BODY_TYPE PLUMBING
J 2
(100 2100);
DISPLAY 1.234043 (100 2100);
PAINT GREEN (100 2100);
DISPLAY INVISIBLE (100 2100);
FORCEPROP 1 LAST HDL_TAP TRUE
J 2
(-225 2025);
DISPLAY 1.234043 (-225 2025);
PAINT GREEN (-225 2025);
DISPLAY INVISIBLE (-225 2025);
FORCEPROP 1 LAST PATH I79
J 2
(102 2150);
DISPLAY 0.872340 (102 2150);
PAINT GREEN (102 2150);
DISPLAY INVISIBLE (102 2150);
FORCEADD OFFPAGE..5
(-2425 2000);
FORCEPROP 2 LAST $XR0 43 
J 0
(-2649 2000);
DISPLAY 0.638298 (-2649 2000);
PAINT MONO (-2649 2000);
FORCEPROP 2 LAST $XR1 45 
J 0
(-2739 2000);
DISPLAY 0.638298 (-2739 2000);
PAINT MONO (-2739 2000);
FORCEPROP 2 LAST $XR2 46 
J 0
(-2829 2000);
DISPLAY 0.638298 (-2829 2000);
PAINT MONO (-2829 2000);
FORCEPROP 2 LAST $XR3 47 
J 0
(-2919 2000);
DISPLAY 0.638298 (-2919 2000);
PAINT MONO (-2919 2000);
FORCEPROP 2 LAST $XR4 48 
J 0
(-3009 2000);
DISPLAY 0.638298 (-3009 2000);
PAINT MONO (-3009 2000);
FORCEPROP 2 LAST $XR5 49 
J 0
(-3099 2000);
DISPLAY 0.638298 (-3099 2000);
PAINT MONO (-3099 2000);
FORCEPROP 2 LAST $XR6 50 
J 0
(-3189 2000);
DISPLAY 0.638298 (-3189 2000);
PAINT MONO (-3189 2000);
FORCEPROP 2 LAST $XR7 51 
J 0
(-3279 2000);
DISPLAY 0.638298 (-3279 2000);
PAINT MONO (-3279 2000);
FORCEPROP 2 LAST $XR8 52 
J 0
(-3369 2000);
DISPLAY 0.638298 (-3369 2000);
PAINT MONO (-3369 2000);
FORCEPROP 2 LAST $XR9 53 
J 0
(-3459 2000);
DISPLAY 0.638298 (-3459 2000);
PAINT MONO (-3459 2000);
FORCEPROP 2 LAST $XR10 54 
J 0
(-2649 1964);
DISPLAY 0.638298 (-2649 1964);
PAINT MONO (-2649 1964);
FORCEPROP 2 LAST $XR11 77 
J 0
(-2739 1964);
DISPLAY 0.638298 (-2739 1964);
PAINT MONO (-2739 1964);
FORCEPROP 2 LAST $XR12 78 
J 0
(-2829 1964);
DISPLAY 0.638298 (-2829 1964);
PAINT MONO (-2829 1964);
FORCEPROP 2 LAST $XR13 79 
J 0
(-2919 1964);
DISPLAY 0.638298 (-2919 1964);
PAINT MONO (-2919 1964);
FORCEPROP 2 LAST $XR14 80 
J 0
(-3009 1964);
DISPLAY 0.638298 (-3009 1964);
PAINT MONO (-3009 1964);
FORCEPROP 2 LAST $XR15 81 
J 0
(-3099 1964);
DISPLAY 0.638298 (-3099 1964);
PAINT MONO (-3099 1964);
FORCEPROP 2 LAST $XR16 82 
J 0
(-3189 1964);
DISPLAY 0.638298 (-3189 1964);
PAINT MONO (-3189 1964);
FORCEPROP 2 LAST $XR17 83 
J 0
(-3279 1964);
DISPLAY 0.638298 (-3279 1964);
PAINT MONO (-3279 1964);
FORCEPROP 2 LAST $XR18 84 
J 0
(-3369 1964);
DISPLAY 0.638298 (-3369 1964);
PAINT MONO (-3369 1964);
FORCEPROP 2 LAST $XR19 85 
J 0
(-3459 1964);
DISPLAY 0.638298 (-3459 1964);
PAINT MONO (-3459 1964);
FORCEPROP 2 LAST $XR20 86 
J 0
(-2649 2036);
DISPLAY 0.638298 (-2649 2036);
PAINT MONO (-2649 2036);
FORCEPROP 2 LAST $XR21 87 
J 0
(-2739 2036);
DISPLAY 0.638298 (-2739 2036);
PAINT MONO (-2739 2036);
FORCEPROP 2 LAST $XR22 88 
J 0
(-2829 2036);
DISPLAY 0.638298 (-2829 2036);
PAINT MONO (-2829 2036);
FORCEPROP 2 LAST $XR23 94 
J 0
(-2919 2036);
DISPLAY 0.638298 (-2919 2036);
PAINT MONO (-2919 2036);
FORCEPROP 2 LAST CDS_LIB mstr_standard
J 0
(-2425 2000);
DISPLAY 0.787234 (-2425 2000);
PAINT MONO (-2425 2000);
DISPLAY INVISIBLE (-2425 2000);
FORCEPROP 1 LAST OFFPAGE TRUE
J 0
(-2100 1875);
DISPLAY 1.404255 (-2100 1875);
PAINT GREEN (-2100 1875);
DISPLAY INVISIBLE (-2100 1875);
FORCEPROP 1 LAST COMMENT_BODY TRUE
J 0
(-2325 1925);
DISPLAY 1.404255 (-2325 1925);
PAINT GREEN (-2325 1925);
DISPLAY INVISIBLE (-2325 1925);
FORCEPROP 2 LAST PATH I8
J 0
(-2625 2050);
DISPLAY 1.021277 (-2625 2050);
PAINT ORANGE (-2625 2050);
DISPLAY INVISIBLE (-2625 2050);
FORCEADD TAP..6
R 2
(100 2250);
FORCEPROP 3 LASTPIN (50 2250) SIG_NAME M_A_DQ<21>
J 0
(60 2260);
DISPLAY 0.659574 (60 2260);
PAINT MONO (60 2260);
DISPLAY INVISIBLE (60 2260);
FORCEPROP 1 LASTPIN (50 2250) BN 21
J 2
(100 2260);
DISPLAY 0.617021 (100 2260);
PAINT PINK (100 2260);
FORCEPROP 2 LAST CDS_LIB mstr_standard
J 2
(100 2250);
DISPLAY 0.787234 (100 2250);
PAINT MONO (100 2250);
DISPLAY INVISIBLE (100 2250);
FORCEPROP 1 LAST BODY_TYPE PLUMBING
J 2
(100 2200);
DISPLAY 1.234043 (100 2200);
PAINT GREEN (100 2200);
DISPLAY INVISIBLE (100 2200);
FORCEPROP 1 LAST HDL_TAP TRUE
J 2
(-225 2125);
DISPLAY 1.234043 (-225 2125);
PAINT GREEN (-225 2125);
DISPLAY INVISIBLE (-225 2125);
FORCEPROP 1 LAST PATH I80
J 2
(102 2250);
DISPLAY 0.872340 (102 2250);
PAINT GREEN (102 2250);
DISPLAY INVISIBLE (102 2250);
FORCEADD TAP..6
R 2
(100 2200);
FORCEPROP 3 LASTPIN (50 2200) SIG_NAME M_A_DQ<20>
J 0
(60 2210);
DISPLAY 0.659574 (60 2210);
PAINT MONO (60 2210);
DISPLAY INVISIBLE (60 2210);
FORCEPROP 1 LASTPIN (50 2200) BN 20
J 2
(100 2210);
DISPLAY 0.617021 (100 2210);
PAINT PINK (100 2210);
FORCEPROP 2 LAST CDS_LIB mstr_standard
J 2
(100 2200);
DISPLAY 0.787234 (100 2200);
PAINT MONO (100 2200);
DISPLAY INVISIBLE (100 2200);
FORCEPROP 1 LAST BODY_TYPE PLUMBING
J 2
(100 2150);
DISPLAY 1.234043 (100 2150);
PAINT GREEN (100 2150);
DISPLAY INVISIBLE (100 2150);
FORCEPROP 1 LAST HDL_TAP TRUE
J 2
(-225 2075);
DISPLAY 1.234043 (-225 2075);
PAINT GREEN (-225 2075);
DISPLAY INVISIBLE (-225 2075);
FORCEPROP 1 LAST PATH I81
J 2
(102 2200);
DISPLAY 0.872340 (102 2200);
PAINT GREEN (102 2200);
DISPLAY INVISIBLE (102 2200);
FORCEADD TAP..6
R 2
(100 2300);
FORCEPROP 3 LASTPIN (50 2300) SIG_NAME M_A_DQ<22>
J 0
(60 2310);
DISPLAY 0.659574 (60 2310);
PAINT MONO (60 2310);
DISPLAY INVISIBLE (60 2310);
FORCEPROP 1 LASTPIN (50 2300) BN 22
J 2
(100 2310);
DISPLAY 0.617021 (100 2310);
PAINT PINK (100 2310);
FORCEPROP 2 LAST CDS_LIB mstr_standard
J 2
(100 2300);
DISPLAY 0.787234 (100 2300);
PAINT MONO (100 2300);
DISPLAY INVISIBLE (100 2300);
FORCEPROP 1 LAST BODY_TYPE PLUMBING
J 2
(100 2250);
DISPLAY 1.234043 (100 2250);
PAINT GREEN (100 2250);
DISPLAY INVISIBLE (100 2250);
FORCEPROP 1 LAST HDL_TAP TRUE
J 2
(-225 2175);
DISPLAY 1.234043 (-225 2175);
PAINT GREEN (-225 2175);
DISPLAY INVISIBLE (-225 2175);
FORCEPROP 1 LAST PATH I82
J 2
(102 2300);
DISPLAY 0.872340 (102 2300);
PAINT GREEN (102 2300);
DISPLAY INVISIBLE (102 2300);
FORCEADD TAP..6
R 2
(100 2350);
FORCEPROP 3 LASTPIN (50 2350) SIG_NAME M_A_DQ<23>
J 0
(60 2360);
DISPLAY 0.659574 (60 2360);
PAINT MONO (60 2360);
DISPLAY INVISIBLE (60 2360);
FORCEPROP 1 LASTPIN (50 2350) BN 23
J 2
(100 2360);
DISPLAY 0.617021 (100 2360);
PAINT PINK (100 2360);
FORCEPROP 2 LAST CDS_LIB mstr_standard
J 2
(100 2350);
DISPLAY 0.787234 (100 2350);
PAINT MONO (100 2350);
DISPLAY INVISIBLE (100 2350);
FORCEPROP 1 LAST BODY_TYPE PLUMBING
J 2
(100 2300);
DISPLAY 1.234043 (100 2300);
PAINT GREEN (100 2300);
DISPLAY INVISIBLE (100 2300);
FORCEPROP 1 LAST HDL_TAP TRUE
J 2
(-225 2225);
DISPLAY 1.234043 (-225 2225);
PAINT GREEN (-225 2225);
DISPLAY INVISIBLE (-225 2225);
FORCEPROP 1 LAST PATH I83
J 2
(102 2350);
DISPLAY 0.872340 (102 2350);
PAINT GREEN (102 2350);
DISPLAY INVISIBLE (102 2350);
FORCEADD TAP..6
R 2
(100 2450);
FORCEPROP 3 LASTPIN (50 2450) SIG_NAME M_A_DQ<25>
J 0
(60 2460);
DISPLAY 0.659574 (60 2460);
PAINT MONO (60 2460);
DISPLAY INVISIBLE (60 2460);
FORCEPROP 1 LASTPIN (50 2450) BN 25
J 2
(100 2460);
DISPLAY 0.617021 (100 2460);
PAINT PINK (100 2460);
FORCEPROP 2 LAST CDS_LIB mstr_standard
J 2
(100 2450);
DISPLAY 0.787234 (100 2450);
PAINT MONO (100 2450);
DISPLAY INVISIBLE (100 2450);
FORCEPROP 1 LAST BODY_TYPE PLUMBING
J 2
(100 2400);
DISPLAY 1.234043 (100 2400);
PAINT GREEN (100 2400);
DISPLAY INVISIBLE (100 2400);
FORCEPROP 1 LAST HDL_TAP TRUE
J 2
(-225 2325);
DISPLAY 1.234043 (-225 2325);
PAINT GREEN (-225 2325);
DISPLAY INVISIBLE (-225 2325);
FORCEPROP 1 LAST PATH I84
J 2
(102 2450);
DISPLAY 0.872340 (102 2450);
PAINT GREEN (102 2450);
DISPLAY INVISIBLE (102 2450);
FORCEADD TAP..6
R 2
(100 2500);
FORCEPROP 3 LASTPIN (50 2500) SIG_NAME M_A_DQ<26>
J 0
(60 2510);
DISPLAY 0.659574 (60 2510);
PAINT MONO (60 2510);
DISPLAY INVISIBLE (60 2510);
FORCEPROP 1 LASTPIN (50 2500) BN 26
J 2
(100 2510);
DISPLAY 0.617021 (100 2510);
PAINT PINK (100 2510);
FORCEPROP 2 LAST CDS_LIB mstr_standard
J 2
(100 2500);
DISPLAY 0.787234 (100 2500);
PAINT MONO (100 2500);
DISPLAY INVISIBLE (100 2500);
FORCEPROP 1 LAST BODY_TYPE PLUMBING
J 2
(100 2450);
DISPLAY 1.234043 (100 2450);
PAINT GREEN (100 2450);
DISPLAY INVISIBLE (100 2450);
FORCEPROP 1 LAST HDL_TAP TRUE
J 2
(-225 2375);
DISPLAY 1.234043 (-225 2375);
PAINT GREEN (-225 2375);
DISPLAY INVISIBLE (-225 2375);
FORCEPROP 1 LAST PATH I85
J 2
(102 2500);
DISPLAY 0.872340 (102 2500);
PAINT GREEN (102 2500);
DISPLAY INVISIBLE (102 2500);
FORCEADD TAP..6
R 2
(100 2400);
FORCEPROP 3 LASTPIN (50 2400) SIG_NAME M_A_DQ<24>
J 0
(60 2410);
DISPLAY 0.659574 (60 2410);
PAINT MONO (60 2410);
DISPLAY INVISIBLE (60 2410);
FORCEPROP 1 LASTPIN (50 2400) BN 24
J 2
(100 2410);
DISPLAY 0.617021 (100 2410);
PAINT PINK (100 2410);
FORCEPROP 2 LAST CDS_LIB mstr_standard
J 2
(100 2400);
DISPLAY 0.787234 (100 2400);
PAINT MONO (100 2400);
DISPLAY INVISIBLE (100 2400);
FORCEPROP 1 LAST BODY_TYPE PLUMBING
J 2
(100 2350);
DISPLAY 1.234043 (100 2350);
PAINT GREEN (100 2350);
DISPLAY INVISIBLE (100 2350);
FORCEPROP 1 LAST HDL_TAP TRUE
J 2
(-225 2275);
DISPLAY 1.234043 (-225 2275);
PAINT GREEN (-225 2275);
DISPLAY INVISIBLE (-225 2275);
FORCEPROP 1 LAST PATH I86
J 2
(102 2400);
DISPLAY 0.872340 (102 2400);
PAINT GREEN (102 2400);
DISPLAY INVISIBLE (102 2400);
FORCEADD TAP..6
R 2
(100 2550);
FORCEPROP 3 LASTPIN (50 2550) SIG_NAME M_A_DQ<27>
J 0
(60 2560);
DISPLAY 0.659574 (60 2560);
PAINT MONO (60 2560);
DISPLAY INVISIBLE (60 2560);
FORCEPROP 1 LASTPIN (50 2550) BN 27
J 2
(100 2560);
DISPLAY 0.617021 (100 2560);
PAINT PINK (100 2560);
FORCEPROP 2 LAST CDS_LIB mstr_standard
J 2
(100 2550);
DISPLAY 0.787234 (100 2550);
PAINT MONO (100 2550);
DISPLAY INVISIBLE (100 2550);
FORCEPROP 1 LAST BODY_TYPE PLUMBING
J 2
(100 2500);
DISPLAY 1.234043 (100 2500);
PAINT GREEN (100 2500);
DISPLAY INVISIBLE (100 2500);
FORCEPROP 1 LAST HDL_TAP TRUE
J 2
(-225 2425);
DISPLAY 1.234043 (-225 2425);
PAINT GREEN (-225 2425);
DISPLAY INVISIBLE (-225 2425);
FORCEPROP 1 LAST PATH I87
J 2
(102 2550);
DISPLAY 0.872340 (102 2550);
PAINT GREEN (102 2550);
DISPLAY INVISIBLE (102 2550);
FORCEADD TAP..6
R 2
(100 2600);
FORCEPROP 3 LASTPIN (50 2600) SIG_NAME M_A_DQ<28>
J 0
(60 2610);
DISPLAY 0.659574 (60 2610);
PAINT MONO (60 2610);
DISPLAY INVISIBLE (60 2610);
FORCEPROP 1 LASTPIN (50 2600) BN 28
J 2
(100 2610);
DISPLAY 0.617021 (100 2610);
PAINT PINK (100 2610);
FORCEPROP 2 LAST CDS_LIB mstr_standard
J 2
(100 2600);
DISPLAY 0.787234 (100 2600);
PAINT MONO (100 2600);
DISPLAY INVISIBLE (100 2600);
FORCEPROP 1 LAST BODY_TYPE PLUMBING
J 2
(100 2550);
DISPLAY 1.234043 (100 2550);
PAINT GREEN (100 2550);
DISPLAY INVISIBLE (100 2550);
FORCEPROP 1 LAST HDL_TAP TRUE
J 2
(-225 2475);
DISPLAY 1.234043 (-225 2475);
PAINT GREEN (-225 2475);
DISPLAY INVISIBLE (-225 2475);
FORCEPROP 1 LAST PATH I88
J 2
(102 2600);
DISPLAY 0.872340 (102 2600);
PAINT GREEN (102 2600);
DISPLAY INVISIBLE (102 2600);
FORCEADD TAP..6
R 2
(100 2700);
FORCEPROP 3 LASTPIN (50 2700) SIG_NAME M_A_DQ<30>
J 0
(60 2710);
DISPLAY 0.659574 (60 2710);
PAINT MONO (60 2710);
DISPLAY INVISIBLE (60 2710);
FORCEPROP 1 LASTPIN (50 2700) BN 30
J 2
(100 2710);
DISPLAY 0.617021 (100 2710);
PAINT PINK (100 2710);
FORCEPROP 2 LAST CDS_LIB mstr_standard
J 2
(100 2700);
DISPLAY 0.787234 (100 2700);
PAINT MONO (100 2700);
DISPLAY INVISIBLE (100 2700);
FORCEPROP 1 LAST BODY_TYPE PLUMBING
J 2
(100 2650);
DISPLAY 1.234043 (100 2650);
PAINT GREEN (100 2650);
DISPLAY INVISIBLE (100 2650);
FORCEPROP 1 LAST HDL_TAP TRUE
J 2
(-225 2575);
DISPLAY 1.234043 (-225 2575);
PAINT GREEN (-225 2575);
DISPLAY INVISIBLE (-225 2575);
FORCEPROP 1 LAST PATH I89
J 2
(102 2700);
DISPLAY 0.872340 (102 2700);
PAINT GREEN (102 2700);
DISPLAY INVISIBLE (102 2700);
FORCEADD OFFPAGE..1
(-2100 900);
FORCEPROP 2 LAST $XR0 89 
J 0
(-2321 900);
DISPLAY 0.638298 (-2321 900);
PAINT MONO (-2321 900);
FORCEPROP 2 LAST $XR1 43 
J 0
(-2411 900);
DISPLAY 0.638298 (-2411 900);
PAINT MONO (-2411 900);
FORCEPROP 2 LAST $XR2 45 
J 0
(-2501 900);
DISPLAY 0.638298 (-2501 900);
PAINT MONO (-2501 900);
FORCEPROP 2 LAST $XR3 46 
J 0
(-2591 900);
DISPLAY 0.638298 (-2591 900);
PAINT MONO (-2591 900);
FORCEPROP 2 LAST $XR4 47 
J 0
(-2321 864);
DISPLAY 0.638298 (-2321 864);
PAINT MONO (-2321 864);
FORCEPROP 2 LAST $XR5 48 
J 0
(-2411 864);
DISPLAY 0.638298 (-2411 864);
PAINT MONO (-2411 864);
FORCEPROP 2 LAST CDS_LIB mstr_standard
J 0
(-2100 900);
PAINT ORANGE (-2100 900);
DISPLAY INVISIBLE (-2100 900);
FORCEPROP 1 LAST OFFPAGE TRUE
J 0
(-1775 775);
DISPLAY 0.936170 (-1775 775);
PAINT GREEN (-1775 775);
DISPLAY INVISIBLE (-1775 775);
FORCEPROP 1 LAST COMMENT_BODY TRUE
J 0
(-1975 800);
DISPLAY 0.936170 (-1975 800);
PAINT GREEN (-1975 800);
DISPLAY INVISIBLE (-1975 800);
FORCEPROP 2 LAST PATH I9
J 0
(-2350 950);
DISPLAY 1.021277 (-2350 950);
PAINT ORANGE (-2350 950);
DISPLAY INVISIBLE (-2350 950);
FORCEADD TAP..6
R 2
(100 2650);
FORCEPROP 3 LASTPIN (50 2650) SIG_NAME M_A_DQ<29>
J 0
(60 2660);
DISPLAY 0.659574 (60 2660);
PAINT MONO (60 2660);
DISPLAY INVISIBLE (60 2660);
FORCEPROP 1 LASTPIN (50 2650) BN 29
J 2
(100 2660);
DISPLAY 0.617021 (100 2660);
PAINT PINK (100 2660);
FORCEPROP 2 LAST CDS_LIB mstr_standard
J 2
(100 2650);
DISPLAY 0.787234 (100 2650);
PAINT MONO (100 2650);
DISPLAY INVISIBLE (100 2650);
FORCEPROP 1 LAST BODY_TYPE PLUMBING
J 2
(100 2600);
DISPLAY 1.234043 (100 2600);
PAINT GREEN (100 2600);
DISPLAY INVISIBLE (100 2600);
FORCEPROP 1 LAST HDL_TAP TRUE
J 2
(-225 2525);
DISPLAY 1.234043 (-225 2525);
PAINT GREEN (-225 2525);
DISPLAY INVISIBLE (-225 2525);
FORCEPROP 1 LAST PATH I90
J 2
(102 2650);
DISPLAY 0.872340 (102 2650);
PAINT GREEN (102 2650);
DISPLAY INVISIBLE (102 2650);
FORCEADD TAP..6
R 2
(100 2750);
FORCEPROP 3 LASTPIN (50 2750) SIG_NAME M_A_DQ<31>
J 0
(60 2760);
DISPLAY 0.659574 (60 2760);
PAINT MONO (60 2760);
DISPLAY INVISIBLE (60 2760);
FORCEPROP 1 LASTPIN (50 2750) BN 31
J 2
(100 2760);
DISPLAY 0.617021 (100 2760);
PAINT PINK (100 2760);
FORCEPROP 2 LAST CDS_LIB mstr_standard
J 2
(100 2750);
DISPLAY 0.787234 (100 2750);
PAINT MONO (100 2750);
DISPLAY INVISIBLE (100 2750);
FORCEPROP 1 LAST BODY_TYPE PLUMBING
J 2
(100 2700);
DISPLAY 1.234043 (100 2700);
PAINT GREEN (100 2700);
DISPLAY INVISIBLE (100 2700);
FORCEPROP 1 LAST HDL_TAP TRUE
J 2
(-225 2625);
DISPLAY 1.234043 (-225 2625);
PAINT GREEN (-225 2625);
DISPLAY INVISIBLE (-225 2625);
FORCEPROP 1 LAST PATH I91
J 2
(102 2750);
DISPLAY 0.872340 (102 2750);
PAINT GREEN (102 2750);
DISPLAY INVISIBLE (102 2750);
FORCEADD TAP..6
R 2
(100 2800);
FORCEPROP 3 LASTPIN (50 2800) SIG_NAME M_A_DQ<32>
J 0
(60 2810);
DISPLAY 0.659574 (60 2810);
PAINT MONO (60 2810);
DISPLAY INVISIBLE (60 2810);
FORCEPROP 1 LASTPIN (50 2800) BN 32
J 2
(100 2810);
DISPLAY 0.617021 (100 2810);
PAINT PINK (100 2810);
FORCEPROP 2 LAST CDS_LIB mstr_standard
J 2
(100 2800);
DISPLAY 0.787234 (100 2800);
PAINT MONO (100 2800);
DISPLAY INVISIBLE (100 2800);
FORCEPROP 1 LAST BODY_TYPE PLUMBING
J 2
(100 2750);
DISPLAY 1.234043 (100 2750);
PAINT GREEN (100 2750);
DISPLAY INVISIBLE (100 2750);
FORCEPROP 1 LAST HDL_TAP TRUE
J 2
(-225 2675);
DISPLAY 1.234043 (-225 2675);
PAINT GREEN (-225 2675);
DISPLAY INVISIBLE (-225 2675);
FORCEPROP 1 LAST PATH I92
J 2
(102 2800);
DISPLAY 0.872340 (102 2800);
PAINT GREEN (102 2800);
DISPLAY INVISIBLE (102 2800);
FORCEADD TAP..6
R 2
(100 2850);
FORCEPROP 3 LASTPIN (50 2850) SIG_NAME M_A_DQ<33>
J 0
(60 2860);
DISPLAY 0.659574 (60 2860);
PAINT MONO (60 2860);
DISPLAY INVISIBLE (60 2860);
FORCEPROP 1 LASTPIN (50 2850) BN 33
J 2
(100 2860);
DISPLAY 0.617021 (100 2860);
PAINT PINK (100 2860);
FORCEPROP 2 LAST CDS_LIB mstr_standard
J 2
(100 2850);
DISPLAY 0.787234 (100 2850);
PAINT MONO (100 2850);
DISPLAY INVISIBLE (100 2850);
FORCEPROP 1 LAST BODY_TYPE PLUMBING
J 2
(100 2800);
DISPLAY 1.234043 (100 2800);
PAINT GREEN (100 2800);
DISPLAY INVISIBLE (100 2800);
FORCEPROP 1 LAST HDL_TAP TRUE
J 2
(-225 2725);
DISPLAY 1.234043 (-225 2725);
PAINT GREEN (-225 2725);
DISPLAY INVISIBLE (-225 2725);
FORCEPROP 1 LAST PATH I93
J 2
(102 2850);
DISPLAY 0.872340 (102 2850);
PAINT GREEN (102 2850);
DISPLAY INVISIBLE (102 2850);
FORCEADD TAP..6
R 2
(100 2900);
FORCEPROP 3 LASTPIN (50 2900) SIG_NAME M_A_DQ<34>
J 0
(60 2910);
DISPLAY 0.659574 (60 2910);
PAINT MONO (60 2910);
DISPLAY INVISIBLE (60 2910);
FORCEPROP 1 LASTPIN (50 2900) BN 34
J 2
(100 2910);
DISPLAY 0.617021 (100 2910);
PAINT PINK (100 2910);
FORCEPROP 2 LAST CDS_LIB mstr_standard
J 2
(100 2900);
DISPLAY 0.787234 (100 2900);
PAINT MONO (100 2900);
DISPLAY INVISIBLE (100 2900);
FORCEPROP 1 LAST BODY_TYPE PLUMBING
J 2
(100 2850);
DISPLAY 1.234043 (100 2850);
PAINT GREEN (100 2850);
DISPLAY INVISIBLE (100 2850);
FORCEPROP 1 LAST HDL_TAP TRUE
J 2
(-225 2775);
DISPLAY 1.234043 (-225 2775);
PAINT GREEN (-225 2775);
DISPLAY INVISIBLE (-225 2775);
FORCEPROP 1 LAST PATH I94
J 2
(102 2900);
DISPLAY 0.872340 (102 2900);
PAINT GREEN (102 2900);
DISPLAY INVISIBLE (102 2900);
FORCEADD TAP..6
R 2
(100 2950);
FORCEPROP 3 LASTPIN (50 2950) SIG_NAME M_A_DQ<35>
J 0
(60 2960);
DISPLAY 0.659574 (60 2960);
PAINT MONO (60 2960);
DISPLAY INVISIBLE (60 2960);
FORCEPROP 1 LASTPIN (50 2950) BN 35
J 2
(100 2960);
DISPLAY 0.617021 (100 2960);
PAINT PINK (100 2960);
FORCEPROP 2 LAST CDS_LIB mstr_standard
J 2
(100 2950);
DISPLAY 0.787234 (100 2950);
PAINT MONO (100 2950);
DISPLAY INVISIBLE (100 2950);
FORCEPROP 1 LAST BODY_TYPE PLUMBING
J 2
(100 2900);
DISPLAY 1.234043 (100 2900);
PAINT GREEN (100 2900);
DISPLAY INVISIBLE (100 2900);
FORCEPROP 1 LAST HDL_TAP TRUE
J 2
(-225 2825);
DISPLAY 1.234043 (-225 2825);
PAINT GREEN (-225 2825);
DISPLAY INVISIBLE (-225 2825);
FORCEPROP 1 LAST PATH I95
J 2
(102 2950);
DISPLAY 0.872340 (102 2950);
PAINT GREEN (102 2950);
DISPLAY INVISIBLE (102 2950);
FORCEADD TAP..6
R 2
(100 3000);
FORCEPROP 3 LASTPIN (50 3000) SIG_NAME M_A_DQ<36>
J 0
(60 3010);
DISPLAY 0.659574 (60 3010);
PAINT MONO (60 3010);
DISPLAY INVISIBLE (60 3010);
FORCEPROP 1 LASTPIN (50 3000) BN 36
J 2
(100 3010);
DISPLAY 0.617021 (100 3010);
PAINT PINK (100 3010);
FORCEPROP 2 LAST CDS_LIB mstr_standard
J 2
(100 3000);
DISPLAY 0.787234 (100 3000);
PAINT MONO (100 3000);
DISPLAY INVISIBLE (100 3000);
FORCEPROP 1 LAST BODY_TYPE PLUMBING
J 2
(100 2950);
DISPLAY 1.234043 (100 2950);
PAINT GREEN (100 2950);
DISPLAY INVISIBLE (100 2950);
FORCEPROP 1 LAST HDL_TAP TRUE
J 2
(-225 2875);
DISPLAY 1.234043 (-225 2875);
PAINT GREEN (-225 2875);
DISPLAY INVISIBLE (-225 2875);
FORCEPROP 1 LAST PATH I96
J 2
(102 3000);
DISPLAY 0.872340 (102 3000);
PAINT GREEN (102 3000);
DISPLAY INVISIBLE (102 3000);
FORCEADD PVDDQ_ABC..1
(600 2200);
FORCEPROP 3 LASTPIN (600 2150) SIG_NAME PVDDQ_ABC\g
J 0
(610 2160);
DISPLAY 0.659574 (610 2160);
PAINT MONO (610 2160);
DISPLAY INVISIBLE (610 2160);
FORCEPROP 1 LAST VOLTAGE 1.2V
J 0
(555 2157);
DISPLAY 0.340426 (555 2157);
PAINT SKYBLUE (555 2157);
DISPLAY INVISIBLE (555 2157);
FORCEPROP 2 LAST BOM_COST MEM
J 0
(600 2205);
PAINT ORANGE (600 2205);
DISPLAY INVISIBLE (600 2205);
FORCEPROP 2 LAST CDS_LIB mstr_symbols
J 0
(600 2200);
PAINT ORANGE (600 2200);
DISPLAY INVISIBLE (600 2200);
FORCEPROP 1 LAST BODY_TYPE PLUMBING
J 0
(555 2157);
DISPLAY 0.340426 (555 2157);
PAINT GREEN (555 2157);
DISPLAY INVISIBLE (555 2157);
FORCEPROP 1 LAST PATH I97
J 0
(650 2225);
DISPLAY 0.872340 (650 2225);
PAINT AQUA (650 2225);
DISPLAY INVISIBLE (650 2225);
FORCEPROP 2 LAST ROOM DDR4_CH_A
J 0
(600 2300);
DISPLAY 0.787234 (600 2300);
PAINT ORANGE (600 2300);
DISPLAY INVISIBLE (600 2300);
FORCEPROP 1 LAST HDL_POWER PVDDQ_ABC
J 1
(600 2250);
DISPLAY 0.872340 (600 2250);
PAINT GREEN (600 2250);
DISPLAY INVISIBLE (600 2250);
FORCEADD TAP..6
R 2
(100 3050);
FORCEPROP 3 LASTPIN (50 3050) SIG_NAME M_A_DQ<37>
J 0
(60 3060);
DISPLAY 0.659574 (60 3060);
PAINT MONO (60 3060);
DISPLAY INVISIBLE (60 3060);
FORCEPROP 1 LASTPIN (50 3050) BN 37
J 2
(100 3060);
DISPLAY 0.617021 (100 3060);
PAINT PINK (100 3060);
FORCEPROP 2 LAST CDS_LIB mstr_standard
J 2
(100 3050);
DISPLAY 0.787234 (100 3050);
PAINT MONO (100 3050);
DISPLAY INVISIBLE (100 3050);
FORCEPROP 1 LAST BODY_TYPE PLUMBING
J 2
(100 3000);
DISPLAY 1.234043 (100 3000);
PAINT GREEN (100 3000);
DISPLAY INVISIBLE (100 3000);
FORCEPROP 1 LAST HDL_TAP TRUE
J 2
(-225 2925);
DISPLAY 1.234043 (-225 2925);
PAINT GREEN (-225 2925);
DISPLAY INVISIBLE (-225 2925);
FORCEPROP 1 LAST PATH I98
J 2
(102 3050);
DISPLAY 0.872340 (102 3050);
PAINT GREEN (102 3050);
DISPLAY INVISIBLE (102 3050);
FORCEADD TAP..6
R 2
(100 3100);
FORCEPROP 3 LASTPIN (50 3100) SIG_NAME M_A_DQ<38>
J 0
(60 3110);
DISPLAY 0.659574 (60 3110);
PAINT MONO (60 3110);
DISPLAY INVISIBLE (60 3110);
FORCEPROP 1 LASTPIN (50 3100) BN 38
J 2
(100 3110);
DISPLAY 0.617021 (100 3110);
PAINT PINK (100 3110);
FORCEPROP 2 LAST CDS_LIB mstr_standard
J 2
(100 3100);
DISPLAY 0.787234 (100 3100);
PAINT MONO (100 3100);
DISPLAY INVISIBLE (100 3100);
FORCEPROP 1 LAST BODY_TYPE PLUMBING
J 2
(100 3050);
DISPLAY 1.234043 (100 3050);
PAINT GREEN (100 3050);
DISPLAY INVISIBLE (100 3050);
FORCEPROP 1 LAST HDL_TAP TRUE
J 2
(-225 2975);
DISPLAY 1.234043 (-225 2975);
PAINT GREEN (-225 2975);
DISPLAY INVISIBLE (-225 2975);
FORCEPROP 1 LAST PATH I99
J 2
(102 3100);
DISPLAY 0.872340 (102 3100);
PAINT GREEN (102 3100);
DISPLAY INVISIBLE (102 3100);
FORCEADD BOM_NOTE..1
(-3325 4925);
FORCEPROP 0 LAST L1 UNSTUFF FOR SKU B
J 0
(-3475 4825);
DISPLAY 1.063830 (-3475 4825);
PAINT WHITE (-3475 4825);
FORCEPROP 2 LAST CDS_LIB mstr_symbols
J 0
(-3325 4925);
PAINT ORANGE (-3325 4925);
DISPLAY INVISIBLE (-3325 4925);
FORCEPROP 2 LAST BOM_COST SB
J 0
(-3475 4900);
DISPLAY 1.361702 (-3475 4900);
PAINT ORANGE (-3475 4900);
DISPLAY INVISIBLE (-3475 4900);
FORCEPROP 1 LAST COMMENT_BODY TRUE
J 0
(-3300 5025);
DISPLAY 1.319149 (-3300 5025);
PAINT ORANGE (-3300 5025);
DISPLAY INVISIBLE (-3300 5025);
FORCEPROP 2 LAST ROOM SB_HEADERS
J 0
(-3475 4900);
DISPLAY 1.361702 (-3475 4900);
PAINT ORANGE (-3475 4900);
DISPLAY INVISIBLE (-3475 4900);
FORCEADD INTEL_CORP_BPAGE..1
(4250 200);
FORCEPROP 1 LAST CDS_CON_LAST_MODIFIED Tue Dec 01 11:51:26 2015
J 0
(2825 525);
PAINT ORANGE (2825 525);
DISPLAY INVISIBLE (2825 525);
FORCEPROP 1 LAST CUSTOM_TXT_CDS <CURRENT_DESIGN_SHEET> OF <TOTAL_DESIGN_SHEETS>
J 0
(3750 225);
PAINT GREEN (3750 225);
FORCEPROP 1 LAST CUSTOM_TXT_CDS <CON_LAST_MODIFIED>
J 0
(2325 550);
PAINT GREEN (2325 550);
FORCEPROP 2 LAST CUSTOM_TXT_CDS <XR_PAGE_TITLE>
J 0
(-3640 5450);
DISPLAY 0.638298 (-3640 5450);
PAINT PINK (-3640 5450);
DISPLAY INVISIBLE (-3640 5450);
FORCEPROP 1 LAST SCH_ADDRESS3 Santa Clara, CA 95052-8119
J 0
(275 225);
DISPLAY 0.617021 (275 225);
PAINT GREEN (275 225);
FORCEPROP 1 LAST SCH_ADDRESS2 P.O. BOX 58119
J 0
(275 275);
DISPLAY 0.617021 (275 275);
PAINT GREEN (275 275);
FORCEPROP 1 LAST SCH_ADDRESS1 2200 Mission College Blvd.
J 0
(275 325);
DISPLAY 0.617021 (275 325);
PAINT GREEN (275 325);
FORCEPROP 1 LAST SCH_TITLE CPU0 DDR4 CH A DIMM1
J 0
(-3700 250);
DISPLAY 1.212766 (-3700 250);
PAINT ORANGE (-3700 250);
FORCEPROP 1 LAST SCH_NUMBER H4694802
J 0
(2950 350);
DISPLAY 1.212766 (2950 350);
PAINT YELLOW (2950 350);
FORCEPROP 1 LAST SCH_DEPT BESD
J 1
(-200 300);
DISPLAY 1.212766 (-200 300);
PAINT YELLOW (-200 300);
FORCEPROP 1 LAST SCH_REV 2.420
J 0
(4000 350);
DISPLAY 0.978723 (4000 350);
PAINT YELLOW (4000 350);
FORCEPROP 2 LAST PAGE_BORDER TRUE
J 0
(-3640 5450);
DISPLAY 0.638298 (-3640 5450);
PAINT PINK (-3640 5450);
DISPLAY INVISIBLE (-3640 5450);
FORCEPROP 2 LAST CDS_LIB mstr_symbols
J 0
(4250 200);
PAINT MONO (4250 200);
DISPLAY INVISIBLE (4250 200);
FORCEPROP 1 LAST COMMENT_BODY TRUE
J 0
(4262 212);
DISPLAY 0.468085 (4262 212);
PAINT GREEN (4262 212);
DISPLAY INVISIBLE (4262 212);
FORCEPROP 2 LAST CDS_XR_PAGE_TITLE CR-44 : @BASEBOARD_FAB2_LIB.BASEBOARD_FAB2(SCH_1):PAGE44
J 0
(-3640 5450);
DISPLAY 0.638298 (-3640 5450);
PAINT PINK (-3640 5450);
DISPLAY INVISIBLE (-3640 5450);
WIRE 17 -1 (2600 4725)(2600 4825);
WIRE 17 -1 (2600 4625)(2600 4725);
WIRE 17 -1 (2600 4825)(2600 4850);
WIRE 17 -1 (3200 4850)(2600 4850);
FORCEPROP 2 LAST SIG_NAME M_A_DQS_DN<17:0>
J 0
(2650 4860);
DISPLAY 0.617021 (2650 4860);
PAINT ORANGE (2650 4860);
WIRE 17 -1 (2400 4575)(2400 4675);
WIRE 17 -1 (2400 4475)(2400 4575);
WIRE 17 -1 (2400 4675)(2400 4775);
WIRE 17 -1 (2400 4775)(2400 4875);
WIRE 17 -1 (2400 4375)(2400 4475);
WIRE 17 -1 (2400 4275)(2400 4375);
WIRE 17 -1 (2400 4875)(2400 4900);
WIRE 17 -1 (3200 4900)(2400 4900);
FORCEPROP 2 LAST SIG_NAME M_A_DQS_DP<17:0>
J 0
(2650 4910);
DISPLAY 0.617021 (2650 4910);
PAINT ORANGE (2650 4910);
WIRE 17 -1 (2600 4125)(2600 4225);
WIRE 17 -1 (2600 4025)(2600 4125);
WIRE 17 -1 (2600 4225)(2600 4325);
WIRE 17 -1 (2600 4325)(2600 4425);
WIRE 17 -1 (2600 3925)(2600 4025);
WIRE 17 -1 (2600 3825)(2600 3925);
WIRE 17 -1 (2600 4425)(2600 4525);
WIRE 17 -1 (2600 4525)(2600 4625);
WIRE 17 -1 (2600 3725)(2600 3825);
WIRE 17 -1 (2600 3625)(2600 3725);
WIRE 17 -1 (2600 3525)(2600 3625);
WIRE 17 -1 (2600 3425)(2600 3525);
WIRE 17 -1 (2400 4175)(2400 4275);
WIRE 17 -1 (2400 4075)(2400 4175);
WIRE 17 -1 (2400 3975)(2400 4075);
WIRE 17 -1 (2400 3875)(2400 3975);
WIRE 17 -1 (2400 3775)(2400 3875);
WIRE 17 -1 (2400 3675)(2400 3775);
WIRE 17 -1 (2400 3575)(2400 3675);
WIRE 17 -1 (2400 3475)(2400 3575);
WIRE 17 -1 (2600 3325)(2600 3425);
WIRE 17 -1 (2600 3225)(2600 3325);
WIRE 17 -1 (2600 3125)(2600 3225);
WIRE 17 -1 (2400 3375)(2400 3475);
WIRE 17 -1 (2400 3275)(2400 3375);
WIRE 17 -1 (2400 3175)(2400 3275);
WIRE 17 -1 (150 1475)(150 1525);
WIRE 17 -1 (150 1425)(150 1475);
WIRE 17 -1 (150 1525)(150 1575);
WIRE 17 -1 (150 1575)(150 1625);
WIRE 17 -1 (150 1375)(150 1425);
WIRE 17 -1 (150 1325)(150 1375);
WIRE 17 -1 (150 1625)(150 1675);
WIRE 17 -1 (150 1675)(150 1725);
WIRE 17 -1 (150 1275)(150 1325);
WIRE 17 -1 (150 1225)(150 1275);
WIRE 17 -1 (150 1725)(150 1775);
WIRE 17 -1 (150 1775)(150 1825);
WIRE 17 -1 (150 1825)(150 1875);
WIRE 17 -1 (150 1875)(150 1925);
WIRE 17 -1 (150 1925)(150 1975);
WIRE 17 -1 (150 1975)(150 2025);
WIRE 17 -1 (150 2025)(150 2075);
WIRE 17 -1 (150 2075)(150 2125);
WIRE 17 -1 (150 2125)(150 2175);
WIRE 17 -1 (150 2175)(150 2225);
WIRE 17 -1 (150 2225)(150 2275);
WIRE 17 -1 (150 2275)(150 2325);
WIRE 17 -1 (150 2325)(150 2375);
WIRE 17 -1 (150 2375)(150 2425);
WIRE 17 -1 (150 2425)(150 2475);
WIRE 17 -1 (150 2475)(150 2525);
WIRE 17 -1 (150 2525)(150 2575);
WIRE 17 -1 (150 2575)(150 2625);
WIRE 17 -1 (150 2625)(150 2675);
WIRE 17 -1 (150 2675)(150 2725);
WIRE 17 -1 (150 2725)(150 2775);
WIRE 17 -1 (150 2775)(150 2825);
WIRE 17 -1 (150 2825)(150 2875);
WIRE 17 -1 (150 2875)(150 2925);
WIRE 17 -1 (150 2925)(150 2975);
WIRE 17 -1 (150 2975)(150 3025);
WIRE 17 -1 (150 3025)(150 3075);
WIRE 17 -1 (150 3075)(150 3125);
WIRE 17 -1 (150 3125)(150 3175);
WIRE 17 -1 (150 3175)(150 3225);
WIRE 17 -1 (150 3225)(150 3275);
WIRE 17 -1 (150 3275)(150 3325);
WIRE 17 -1 (150 3325)(150 3375);
WIRE 17 -1 (150 3375)(150 3425);
WIRE 17 -1 (150 3425)(150 3475);
WIRE 17 -1 (150 3475)(150 3525);
WIRE 17 -1 (150 3525)(150 3575);
WIRE 17 -1 (150 3575)(150 3625);
WIRE 17 -1 (150 3625)(150 3675);
WIRE 17 -1 (150 3675)(150 3725);
WIRE 17 -1 (150 3725)(150 3775);
WIRE 17 -1 (150 3775)(150 3825);
WIRE 17 -1 (150 3825)(150 3875);
WIRE 17 -1 (150 3875)(150 3925);
WIRE 17 -1 (150 3925)(150 3975);
WIRE 17 -1 (150 3975)(150 4025);
WIRE 17 -1 (150 4025)(150 4075);
WIRE 17 -1 (150 4075)(150 4125);
WIRE 17 -1 (150 4125)(150 4175);
WIRE 17 -1 (150 4175)(150 4225);
WIRE 17 -1 (150 4225)(150 4275);
WIRE 17 -1 (150 4275)(150 4325);
WIRE 17 -1 (150 4325)(150 4375);
WIRE 17 -1 (150 4375)(150 4400);
WIRE 17 -1 (650 4400)(150 4400);
FORCEPROP 2 LAST SIG_NAME M_A_DQ<63:0>
J 0
(190 4410);
DISPLAY 0.617021 (190 4410);
PAINT ORANGE (190 4410);
WIRE 17 -1 (-1500 4275)(-1500 4325);
WIRE 17 -1 (-1500 4225)(-1500 4275);
WIRE 17 -1 (-1500 4325)(-1500 4375);
WIRE 17 -1 (-1500 4375)(-1500 4400);
WIRE 17 -1 (-1500 4175)(-1500 4225);
WIRE 17 -1 (-1500 4125)(-1500 4175);
WIRE 17 -1 (-2050 4400)(-1500 4400);
FORCEPROP 2 LAST SIG_NAME M_A_MA<17:0>
J 0
(-2000 4410);
DISPLAY 0.617021 (-2000 4410);
PAINT ORANGE (-2000 4410);
WIRE 17 -1 (-1500 4075)(-1500 4125);
WIRE 17 -1 (-1500 4025)(-1500 4075);
WIRE 17 -1 (-1500 3975)(-1500 4025);
WIRE 17 -1 (-1500 3925)(-1500 3975);
WIRE 17 -1 (-1500 3875)(-1500 3925);
WIRE 17 -1 (-1500 3625)(-1500 3675);
WIRE 17 -1 (-1500 3575)(-1500 3625);
WIRE 17 -1 (-1500 3675)(-1500 3725);
WIRE 17 -1 (-1500 3725)(-1500 3775);
WIRE 17 -1 (-1500 3525)(-1500 3575);
WIRE 17 -1 (-1500 3775)(-1500 3825);
WIRE 17 -1 (-1500 3825)(-1500 3875);
WIRE 17 -1 (-1500 3375)(-1500 3425);
WIRE 17 -1 (-1500 3450)(-1500 3425);
WIRE 17 -1 (-1500 3450)(-2050 3450);
FORCEPROP 2 LAST SIG_NAME M_A_BA<1:0>
J 0
(-2025 3460);
DISPLAY 0.617021 (-2025 3460);
PAINT ORANGE (-2025 3460);
WIRE 17 -1 (-1500 3325)(-1500 3350);
WIRE 17 -1 (-1500 3275)(-1500 3325);
WIRE 17 -1 (-1500 3350)(-2050 3350);
FORCEPROP 2 LAST SIG_NAME M_A_BG<1:0>
J 0
(-2025 3360);
DISPLAY 0.617021 (-2025 3360);
PAINT ORANGE (-2025 3360);
WIRE 17 -1 (-1500 3175)(-1500 3200);
WIRE 17 -1 (-1500 3075)(-1500 3175);
WIRE 17 -1 (-1500 3200)(-2050 3200);
FORCEPROP 2 LAST SIG_NAME M_A_CLK_DP<3:0>
J 0
(-2025 3210);
DISPLAY 0.617021 (-2025 3210);
PAINT ORANGE (-2025 3210);
WIRE 17 -1 (-1700 3125)(-1700 3150);
WIRE 17 -1 (-1700 3125)(-1700 3025);
WIRE 17 -1 (-1700 3150)(-2050 3150);
FORCEPROP 2 LAST SIG_NAME M_A_CLK_DN<3:0>
J 0
(-2025 3160);
DISPLAY 0.617021 (-2025 3160);
PAINT ORANGE (-2025 3160);
WIRE 17 -1 (-1500 2725)(-1500 2775);
WIRE 17 -1 (-1500 2775)(-1500 2825);
WIRE 17 -1 (-1500 2825)(-1500 2875);
WIRE 17 -1 (-1500 2875)(-1500 2900);
WIRE 17 -1 (-1500 2900)(-2050 2900);
FORCEPROP 2 LAST SIG_NAME M_A_CS_N<7:0>
J 0
(-2025 2910);
DISPLAY 0.617021 (-2025 2910);
PAINT ORANGE (-2025 2910);
WIRE 17 -1 (-1500 2625)(-1500 2650);
WIRE 17 -1 (-1500 2575)(-1500 2625);
WIRE 17 -1 (-1500 2650)(-2050 2650);
FORCEPROP 2 LAST SIG_NAME M_A_CKE<3:0>
J 0
(-2025 2660);
DISPLAY 0.617021 (-2025 2660);
PAINT ORANGE (-2025 2660);
WIRE 17 -1 (-1500 2475)(-1500 2500);
WIRE 17 -1 (-1500 2425)(-1500 2475);
WIRE 17 -1 (-1500 2500)(-2050 2500);
FORCEPROP 2 LAST SIG_NAME M_A_ODT<3:0>
J 0
(-2025 2510);
DISPLAY 0.617021 (-2025 2510);
PAINT ORANGE (-2025 2510);
WIRE 17 -1 (-1500 2275)(-1500 2325);
WIRE 17 -1 (-1500 2225)(-1500 2275);
WIRE 17 -1 (-1500 2325)(-1500 2350);
WIRE 17 -1 (-1500 2350)(-2050 2350);
FORCEPROP 2 LAST SIG_NAME M_A_ECC<7:0>
J 0
(-2025 2360);
DISPLAY 0.617021 (-2025 2360);
PAINT ORANGE (-2025 2360);
WIRE 17 -1 (-1500 2075)(-1500 2125);
WIRE 17 -1 (-1500 2025)(-1500 2075);
WIRE 17 -1 (-1500 2125)(-1500 2175);
WIRE 17 -1 (-1500 2175)(-1500 2225);
WIRE 17 -1 (-1500 1975)(-1500 2025);
WIRE 16 -1 (-2650 900)(-2650 800);
WIRE 16 -1 (1100 2150)(950 2150);
WIRE 16 -1 (950 2150)(950 2200);
WIRE 16 -1 (950 2200)(1100 2200);
WIRE 16 -1 (800 2200)(950 2200);
WIRE 16 -1 (800 2200)(800 2300);
WIRE 16 -1 (950 2300)(1100 2300);
WIRE 16 -1 (950 2300)(950 2350);
WIRE 16 -1 (950 2350)(1100 2350);
WIRE 16 -1 (950 2350)(950 2400);
WIRE 16 -1 (950 2400)(1100 2400);
WIRE 16 -1 (950 2400)(950 2450);
WIRE 16 -1 (950 2450)(1100 2450);
WIRE 16 -1 (950 2500)(950 2450);
WIRE 16 -1 (950 2500)(1100 2500);
WIRE 16 -1 (950 2600)(950 2500);
WIRE 16 -1 (2750 3550)(2950 3550);
WIRE 16 -1 (2750 3500)(2750 3550);
WIRE 16 -1 (2750 3500)(2950 3500);
WIRE 16 -1 (2750 3450)(2750 3500);
WIRE 16 -1 (2750 3450)(2950 3450);
WIRE 16 -1 (2750 3400)(2750 3450);
WIRE 16 -1 (2750 3400)(2950 3400);
WIRE 16 -1 (2750 3350)(2750 3400);
WIRE 16 -1 (2750 3350)(2950 3350);
WIRE 16 -1 (2750 3300)(2750 3350);
WIRE 16 -1 (2750 3300)(2950 3300);
WIRE 16 -1 (2750 3250)(2750 3300);
WIRE 16 -1 (2750 3250)(2950 3250);
WIRE 16 -1 (2750 3200)(2750 3250);
WIRE 16 -1 (2750 3200)(2950 3200);
WIRE 16 -1 (2750 3150)(2750 3200);
WIRE 16 -1 (2750 3150)(2950 3150);
WIRE 16 -1 (2750 3100)(2750 3150);
WIRE 16 -1 (2750 3100)(2950 3100);
WIRE 16 -1 (2750 3050)(2750 3100);
WIRE 16 -1 (2750 3050)(2950 3050);
WIRE 16 -1 (2750 3000)(2750 3050);
WIRE 16 -1 (2750 3000)(2950 3000);
WIRE 16 -1 (2750 2950)(2750 3000);
WIRE 16 -1 (2750 2950)(2950 2950);
WIRE 16 -1 (2750 2900)(2750 2950);
WIRE 16 -1 (2750 2900)(2950 2900);
WIRE 16 -1 (2750 2850)(2750 2900);
WIRE 16 -1 (2750 2850)(2950 2850);
WIRE 16 -1 (2750 2800)(2750 2850);
WIRE 16 -1 (2750 2800)(2950 2800);
WIRE 16 -1 (2750 2750)(2750 2800);
WIRE 16 -1 (2750 2750)(2950 2750);
WIRE 16 -1 (2750 2700)(2750 2750);
WIRE 16 -1 (2750 2700)(2950 2700);
WIRE 16 -1 (2750 2650)(2750 2700);
WIRE 16 -1 (2750 2650)(2950 2650);
WIRE 16 -1 (2750 2600)(2750 2650);
WIRE 16 -1 (2750 2600)(2950 2600);
WIRE 16 -1 (2750 2550)(2750 2600);
WIRE 16 -1 (2750 2550)(2950 2550);
WIRE 16 -1 (2750 2500)(2750 2550);
WIRE 16 -1 (2750 2500)(2950 2500);
WIRE 16 -1 (2750 2450)(2750 2500);
WIRE 16 -1 (2750 2450)(2950 2450);
WIRE 16 -1 (2750 2400)(2750 2450);
WIRE 16 -1 (2750 2400)(2950 2400);
WIRE 16 -1 (2750 2350)(2750 2400);
WIRE 16 -1 (2750 2350)(2950 2350);
WIRE 16 -1 (2750 2300)(2750 2350);
WIRE 16 -1 (2750 2300)(2950 2300);
WIRE 16 -1 (2750 2250)(2750 2300);
WIRE 16 -1 (2750 2250)(2950 2250);
WIRE 16 -1 (2750 2200)(2750 2250);
WIRE 16 -1 (2750 2200)(2950 2200);
WIRE 16 -1 (2750 2150)(2750 2200);
WIRE 16 -1 (2750 2150)(2950 2150);
WIRE 16 -1 (2750 2100)(2750 2150);
WIRE 16 -1 (2750 2100)(2950 2100);
WIRE 16 -1 (2750 2050)(2750 2100);
WIRE 16 -1 (2750 2050)(2950 2050);
WIRE 16 -1 (2750 2000)(2750 2050);
WIRE 16 -1 (2750 2000)(2950 2000);
WIRE 16 -1 (2750 1950)(2750 2000);
WIRE 16 -1 (2750 1950)(2950 1950);
WIRE 16 -1 (2750 1900)(2750 1950);
WIRE 16 -1 (2750 1900)(2950 1900);
WIRE 16 -1 (2750 1850)(2750 1900);
WIRE 16 -1 (2750 1850)(2950 1850);
WIRE 16 -1 (2750 1800)(2750 1850);
WIRE 16 -1 (2750 1800)(2950 1800);
WIRE 16 -1 (2750 1750)(2750 1800);
WIRE 16 -1 (2750 1750)(2950 1750);
WIRE 16 -1 (2750 1700)(2750 1750);
WIRE 16 -1 (2750 1700)(2950 1700);
WIRE 16 -1 (2750 1650)(2750 1700);
WIRE 16 -1 (2750 1650)(2950 1650);
WIRE 16 -1 (2750 1600)(2750 1650);
WIRE 16 -1 (2750 1600)(2950 1600);
WIRE 16 -1 (2750 1550)(2750 1600);
WIRE 16 -1 (2750 1550)(2950 1550);
WIRE 16 -1 (2750 1500)(2750 1550);
WIRE 16 -1 (2750 1500)(2950 1500);
WIRE 16 -1 (2750 1450)(2750 1500);
WIRE 16 -1 (2750 1450)(2950 1450);
WIRE 16 -1 (2750 1400)(2750 1450);
WIRE 16 -1 (2750 1400)(2950 1400);
WIRE 16 -1 (2750 1350)(2750 1400);
WIRE 16 -1 (2750 1350)(2950 1350);
WIRE 16 -1 (2750 1300)(2750 1350);
WIRE 16 -1 (2750 1300)(2950 1300);
WIRE 16 -1 (2750 1250)(2750 1300);
WIRE 16 -1 (2750 1250)(2950 1250);
WIRE 16 -1 (2750 1150)(2750 1250);
WIRE 16 -1 (4150 3500)(4150 3550);
WIRE 16 -1 (4150 3450)(4150 3500);
WIRE 16 -1 (4150 3500)(3950 3500);
WIRE 16 -1 (4150 3550)(3950 3550);
WIRE 16 -1 (4150 3400)(4150 3450);
WIRE 16 -1 (4150 3450)(3950 3450);
WIRE 16 -1 (4150 3350)(4150 3400);
WIRE 16 -1 (4150 3400)(3950 3400);
WIRE 16 -1 (4150 3300)(4150 3350);
WIRE 16 -1 (4150 3350)(3950 3350);
WIRE 16 -1 (4150 3250)(4150 3300);
WIRE 16 -1 (4150 3300)(3950 3300);
WIRE 16 -1 (4150 3200)(4150 3250);
WIRE 16 -1 (4150 3250)(3950 3250);
WIRE 16 -1 (4150 3150)(4150 3200);
WIRE 16 -1 (4150 3200)(3950 3200);
WIRE 16 -1 (4150 3100)(4150 3150);
WIRE 16 -1 (4150 3150)(3950 3150);
WIRE 16 -1 (4150 3050)(4150 3100);
WIRE 16 -1 (4150 3100)(3950 3100);
WIRE 16 -1 (4150 3000)(4150 3050);
WIRE 16 -1 (4150 3050)(3950 3050);
WIRE 16 -1 (4150 2950)(4150 3000);
WIRE 16 -1 (4150 3000)(3950 3000);
WIRE 16 -1 (4150 2900)(4150 2950);
WIRE 16 -1 (4150 2950)(3950 2950);
WIRE 16 -1 (4150 2850)(4150 2900);
WIRE 16 -1 (4150 2900)(3950 2900);
WIRE 16 -1 (4150 2800)(4150 2850);
WIRE 16 -1 (4150 2850)(3950 2850);
WIRE 16 -1 (4150 2750)(4150 2800);
WIRE 16 -1 (4150 2800)(3950 2800);
WIRE 16 -1 (4150 2700)(4150 2750);
WIRE 16 -1 (4150 2750)(3950 2750);
WIRE 16 -1 (4150 2650)(4150 2700);
WIRE 16 -1 (4150 2700)(3950 2700);
WIRE 16 -1 (4150 2600)(4150 2650);
WIRE 16 -1 (4150 2650)(3950 2650);
WIRE 16 -1 (4150 2550)(4150 2600);
WIRE 16 -1 (4150 2600)(3950 2600);
WIRE 16 -1 (4150 2500)(4150 2550);
WIRE 16 -1 (4150 2550)(3950 2550);
WIRE 16 -1 (4150 2450)(4150 2500);
WIRE 16 -1 (4150 2500)(3950 2500);
WIRE 16 -1 (4150 2400)(4150 2450);
WIRE 16 -1 (4150 2450)(3950 2450);
WIRE 16 -1 (4150 2350)(4150 2400);
WIRE 16 -1 (4150 2400)(3950 2400);
WIRE 16 -1 (4150 2300)(4150 2350);
WIRE 16 -1 (4150 2350)(3950 2350);
WIRE 16 -1 (4150 2250)(4150 2300);
WIRE 16 -1 (4150 2300)(3950 2300);
WIRE 16 -1 (4150 2200)(4150 2250);
WIRE 16 -1 (4150 2250)(3950 2250);
WIRE 16 -1 (4150 2150)(4150 2200);
WIRE 16 -1 (4150 2200)(3950 2200);
WIRE 16 -1 (4150 2100)(4150 2150);
WIRE 16 -1 (4150 2150)(3950 2150);
WIRE 16 -1 (4150 2050)(4150 2100);
WIRE 16 -1 (4150 2100)(3950 2100);
WIRE 16 -1 (4150 2000)(4150 2050);
WIRE 16 -1 (4150 2050)(3950 2050);
WIRE 16 -1 (4150 1950)(4150 2000);
WIRE 16 -1 (4150 2000)(3950 2000);
WIRE 16 -1 (4150 1900)(4150 1950);
WIRE 16 -1 (4150 1950)(3950 1950);
WIRE 16 -1 (4150 1850)(4150 1900);
WIRE 16 -1 (4150 1900)(3950 1900);
WIRE 16 -1 (4150 1800)(4150 1850);
WIRE 16 -1 (4150 1850)(3950 1850);
WIRE 16 -1 (4150 1750)(4150 1800);
WIRE 16 -1 (4150 1800)(3950 1800);
WIRE 16 -1 (4150 1700)(4150 1750);
WIRE 16 -1 (4150 1750)(3950 1750);
WIRE 16 -1 (4150 1650)(4150 1700);
WIRE 16 -1 (4150 1700)(3950 1700);
WIRE 16 -1 (4150 1600)(4150 1650);
WIRE 16 -1 (4150 1650)(3950 1650);
WIRE 16 -1 (4150 1550)(4150 1600);
WIRE 16 -1 (4150 1600)(3950 1600);
WIRE 16 -1 (4150 1500)(4150 1550);
WIRE 16 -1 (4150 1550)(3950 1550);
WIRE 16 -1 (4150 1450)(4150 1500);
WIRE 16 -1 (4150 1500)(3950 1500);
WIRE 16 -1 (4150 1400)(4150 1450);
WIRE 16 -1 (4150 1450)(3950 1450);
WIRE 16 -1 (4150 1350)(4150 1400);
WIRE 16 -1 (4150 1400)(3950 1400);
WIRE 16 -1 (4150 1300)(4150 1350);
WIRE 16 -1 (4150 1350)(3950 1350);
WIRE 16 -1 (4150 1250)(4150 1300);
WIRE 16 -1 (4150 1300)(3950 1300);
WIRE 16 -1 (4150 1150)(4150 1250);
WIRE 16 -1 (4150 1250)(3950 1250);
WIRE 16 -1 (2100 2450)(2300 2450);
WIRE 16 -1 (2300 2450)(2300 2500);
WIRE 16 -1 (2300 2500)(2300 2675);
WIRE 16 -1 (2300 2500)(2100 2500);
WIRE 16 -1 (-1400 1450)(-1200 1450);
WIRE 16 -1 (-1400 1500)(-1400 1450);
WIRE 16 -1 (-1400 1500)(-1200 1500);
WIRE 16 -1 (-3350 1500)(-1400 1500);
WIRE 16 -1 (-3350 1500)(-3350 1400);
WIRE 16 -1 (-1500 1550)(-1500 1400);
WIRE 16 -1 (-1200 1550)(-1500 1550);
WIRE 16 -1 (-1500 1550)(-3350 1550);
WIRE 16 -1 (-1500 1400)(-1200 1400);
WIRE 16 -1 (-3350 1650)(-3350 1550);
WIRE 16 -1 (950 800)(1100 800);
WIRE 16 -1 (950 800)(950 850);
WIRE 16 -1 (950 850)(1100 850);
WIRE 16 -1 (950 850)(950 900);
WIRE 16 -1 (950 900)(1100 900);
WIRE 16 -1 (950 900)(950 950);
WIRE 16 -1 (950 950)(1100 950);
WIRE 16 -1 (950 950)(950 1000);
WIRE 16 -1 (950 1000)(1100 1000);
WIRE 16 -1 (950 1000)(950 1050);
WIRE 16 -1 (950 1050)(1100 1050);
WIRE 16 -1 (950 1050)(950 1100);
WIRE 16 -1 (950 1100)(1100 1100);
WIRE 16 -1 (950 1100)(950 1150);
WIRE 16 -1 (950 1150)(1100 1150);
WIRE 16 -1 (950 1150)(950 1200);
WIRE 16 -1 (950 1200)(1100 1200);
WIRE 16 -1 (950 1200)(950 1250);
WIRE 16 -1 (950 1250)(1100 1250);
WIRE 16 -1 (950 1250)(950 1300);
WIRE 16 -1 (950 1300)(1100 1300);
WIRE 16 -1 (950 1300)(950 1350);
WIRE 16 -1 (950 1350)(1100 1350);
WIRE 16 -1 (950 1350)(950 1400);
WIRE 16 -1 (950 1400)(1100 1400);
WIRE 16 -1 (950 1400)(950 1450);
WIRE 16 -1 (950 1450)(1100 1450);
WIRE 16 -1 (950 1450)(950 1500);
WIRE 16 -1 (950 1500)(1100 1500);
WIRE 16 -1 (950 1500)(950 1550);
WIRE 16 -1 (950 1550)(1100 1550);
WIRE 16 -1 (950 1550)(950 1600);
WIRE 16 -1 (950 1600)(1100 1600);
WIRE 16 -1 (950 1600)(950 1650);
WIRE 16 -1 (950 1650)(1100 1650);
WIRE 16 -1 (950 1650)(950 1700);
WIRE 16 -1 (950 1700)(1100 1700);
WIRE 16 -1 (950 1700)(950 1750);
WIRE 16 -1 (950 1750)(1100 1750);
WIRE 16 -1 (950 1750)(950 1800);
WIRE 16 -1 (950 1800)(1100 1800);
WIRE 16 -1 (950 1800)(950 1850);
WIRE 16 -1 (950 1850)(1100 1850);
WIRE 16 -1 (950 1850)(950 1900);
WIRE 16 -1 (950 1900)(1100 1900);
WIRE 16 -1 (950 1900)(950 1950);
WIRE 16 -1 (950 1950)(1100 1950);
WIRE 16 -1 (950 1950)(950 2000);
WIRE 16 -1 (950 2000)(950 2050);
WIRE 16 -1 (950 2000)(1100 2000);
WIRE 16 -1 (950 2050)(1100 2050);
WIRE 16 -1 (600 2050)(950 2050);
WIRE 16 -1 (600 2150)(600 2050);
WIRE 16 -1 (-2650 1100)(-2650 1200);
WIRE 16 -1 (-1200 1200)(-2650 1200);
FORCEPROP 2 LAST SIG_NAME M_A_VREF
J 0
(-2548 1226);
DISPLAY 0.617021 (-2548 1226);
PAINT ORANGE (-2548 1226);
WIRE 16 -1 (-2750 1200)(-2650 1200);
WIRE 16 -1 (-2050 1050)(-1200 1050);
FORCEPROP 2 LAST SIG_NAME TP_CH_A_DIMM_A1_RFU_1
J 0
(-2000 1060);
DISPLAY 0.617021 (-2000 1060);
PAINT ORANGE (-2000 1060);
FORCEPROP 2 LASTPROP $XRERR UNIQUE?
J 0
(-2290 1050);
DISPLAY 0.638298 (-2290 1050);
PAINT MONO (-2290 1050);
DISPLAY INVISIBLE (-2290 1050);
WIRE 16 -1 (-2050 1100)(-1200 1100);
FORCEPROP 2 LAST SIG_NAME TP_CH_A_DIMM_A1_RFU_2
J 0
(-2000 1110);
DISPLAY 0.617021 (-2000 1110);
PAINT ORANGE (-2000 1110);
FORCEPROP 2 LASTPROP $XRERR UNIQUE?
J 0
(-2290 1100);
DISPLAY 0.638298 (-2290 1100);
PAINT MONO (-2290 1100);
DISPLAY INVISIBLE (-2290 1100);
WIRE 16 -1 (-2050 1000)(-1200 1000);
FORCEPROP 2 LAST SIG_NAME TP_CH_A_DIMM_A1_RFU_0
J 0
(-2000 1010);
DISPLAY 0.617021 (-2000 1010);
PAINT ORANGE (-2000 1010);
FORCEPROP 2 LASTPROP $XRERR UNIQUE?
J 0
(-2290 1000);
DISPLAY 0.638298 (-2290 1000);
PAINT MONO (-2290 1000);
DISPLAY INVISIBLE (-2290 1000);
WIRE 16 -1 (-1200 1350)(-2050 1350);
WIRE 16 -1 (-2050 1300)(-1200 1300);
FORCEPROP 2 LAST SIG_NAME SMB_DDR_ABC_VPP_SCL
J 0
(-2010 1310);
DISPLAY 0.617021 (-2010 1310);
PAINT ORANGE (-2010 1310);
WIRE 16 -1 (-1200 1650)(-2250 1650);
FORCEPROP 2 LAST SIG_NAME M_A_ACT_N
J 0
(-2200 1660);
DISPLAY 0.617021 (-2200 1660);
PAINT ORANGE (-2200 1660);
WIRE 16 -1 (-1200 1700)(-2275 1700);
FORCEPROP 2 LAST SIG_NAME M_A_ALERT_N
J 0
(-2225 1710);
DISPLAY 0.617021 (-2225 1710);
PAINT ORANGE (-2225 1710);
WIRE 16 -1 (-2050 900)(-1200 900);
FORCEPROP 2 LAST SIG_NAME FM_ADR_COMPLETE_ABC_N
J 0
(-2000 910);
DISPLAY 0.617021 (-2000 910);
PAINT ORANGE (-2000 910);
WIRE 16 -1 (-1650 1750)(-1200 1750);
WIRE 16 -1 (-1650 1750)(-1650 2000);
WIRE 16 -1 (-1650 2000)(-2375 2000);
FORCEPROP 2 LAST SIG_NAME FM_DIMM_EVENT_COD_N
J 0
(-2335 2006);
DISPLAY 0.617021 (-2335 2006);
PAINT ORANGE (-2335 2006);
WIRE 16 -1 (-1200 2000)(-1400 2000);
WIRE 16 -1 (-1200 1950)(-1400 1950);
WIRE 16 -1 (-1550 1850)(-1550 2300);
WIRE 16 -1 (-1200 1850)(-1550 1850);
WIRE 16 -1 (-1550 2300)(-2050 2300);
FORCEPROP 2 LAST SIG_NAME M_A_PAR
J 0
(-2025 2310);
DISPLAY 0.617021 (-2025 2310);
PAINT ORANGE (-2025 2310);
WIRE 16 -1 (-1600 1800)(-1600 2250);
WIRE 16 -1 (-1200 1800)(-1600 1800);
WIRE 16 -1 (-1600 2250)(-2050 2250);
FORCEPROP 2 LAST SIG_NAME M_ABC_RST_N
J 0
(-2025 2260);
DISPLAY 0.617021 (-2025 2260);
PAINT ORANGE (-2025 2260);
WIRE 16 -1 (-1200 3000)(-1600 3000);
WIRE 16 -1 (-1200 2250)(-1400 2250);
WIRE 16 -1 (-1200 2200)(-1400 2200);
WIRE 16 -1 (-1200 2150)(-1400 2150);
WIRE 16 -1 (-1200 2100)(-1400 2100);
WIRE 16 -1 (-1200 2050)(-1400 2050);
WIRE 16 -1 (-1200 2300)(-1400 2300);
WIRE 16 -1 (-1200 2400)(-1400 2400);
WIRE 16 -1 (-1200 2450)(-1400 2450);
WIRE 16 -1 (-1200 2550)(-1400 2550);
WIRE 16 -1 (-1350 2900)(-1200 2900);
WIRE 16 -1 (-1350 2950)(-1350 2900);
WIRE 16 -1 (-1350 2950)(-2050 2950);
FORCEPROP 2 LAST SIG_NAME M_A_C<2>
J 0
(-2000 2960);
DISPLAY 0.617021 (-2000 2960);
PAINT ORANGE (-2000 2960);
WIRE 16 -1 (-1200 3050)(-1400 3050);
WIRE 16 -1 (-1200 2850)(-1400 2850);
WIRE 16 -1 (-1200 2800)(-1400 2800);
WIRE 16 -1 (-1200 2750)(-1400 2750);
WIRE 16 -1 (-1200 2600)(-1400 2600);
WIRE 16 -1 (-1200 2700)(-1400 2700);
WIRE 16 -1 (-1200 3100)(-1600 3100);
WIRE 16 -1 (-1200 3400)(-1400 3400);
WIRE 16 -1 (-1200 3500)(-1400 3500);
WIRE 16 -1 (-1200 3550)(-1400 3550);
WIRE 16 -1 (-1200 3150)(-1400 3150);
WIRE 16 -1 (-1200 3250)(-1400 3250);
WIRE 16 -1 (-1200 3300)(-1400 3300);
WIRE 16 -1 (-1200 3350)(-1400 3350);
WIRE 16 -1 (-1200 3700)(-1400 3700);
WIRE 16 -1 (-1200 3750)(-1400 3750);
WIRE 16 -1 (-1200 3800)(-1400 3800);
WIRE 16 -1 (-1200 3850)(-1400 3850);
WIRE 16 -1 (-1200 3900)(-1400 3900);
WIRE 16 -1 (-1200 3950)(-1400 3950);
WIRE 16 -1 (-1200 4000)(-1400 4000);
WIRE 16 -1 (-1200 4050)(-1400 4050);
WIRE 16 -1 (-1200 3650)(-1400 3650);
WIRE 16 -1 (-1200 3600)(-1400 3600);
WIRE 16 -1 (-1200 4100)(-1400 4100);
WIRE 16 -1 (-1200 4150)(-1400 4150);
WIRE 16 -1 (-1200 4350)(-1400 4350);
WIRE 16 -1 (-1200 4200)(-1400 4200);
WIRE 16 -1 (-1200 4250)(-1400 4250);
WIRE 16 -1 (-1200 4300)(-1400 4300);
WIRE 16 -1 (50 4350)(-200 4350);
WIRE 16 -1 (50 2650)(-200 2650);
WIRE 16 -1 (50 2600)(-200 2600);
WIRE 16 -1 (50 4300)(-200 4300);
WIRE 16 -1 (50 4250)(-200 4250);
WIRE 16 -1 (50 4200)(-200 4200);
WIRE 16 -1 (50 4150)(-200 4150);
WIRE 16 -1 (50 4000)(-200 4000);
WIRE 16 -1 (50 3950)(-200 3950);
WIRE 16 -1 (50 3500)(-200 3500);
WIRE 16 -1 (50 3450)(-200 3450);
WIRE 16 -1 (50 3400)(-200 3400);
WIRE 16 -1 (50 3350)(-200 3350);
WIRE 16 -1 (50 3300)(-200 3300);
WIRE 16 -1 (50 3250)(-200 3250);
WIRE 16 -1 (50 3200)(-200 3200);
WIRE 16 -1 (50 3150)(-200 3150);
WIRE 16 -1 (50 2900)(-200 2900);
WIRE 16 -1 (50 2850)(-200 2850);
WIRE 16 -1 (50 2800)(-200 2800);
WIRE 16 -1 (50 2750)(-200 2750);
WIRE 16 -1 (50 2700)(-200 2700);
WIRE 16 -1 (50 2450)(-200 2450);
WIRE 16 -1 (50 2300)(-200 2300);
WIRE 16 -1 (50 2250)(-200 2250);
WIRE 16 -1 (50 2000)(-200 2000);
WIRE 16 -1 (50 1850)(-200 1850);
WIRE 16 -1 (50 1800)(-200 1800);
WIRE 16 -1 (50 1700)(-200 1700);
WIRE 16 -1 (50 1600)(-200 1600);
WIRE 16 -1 (50 1550)(-200 1550);
WIRE 16 -1 (50 1250)(-200 1250);
WIRE 16 -1 (50 1200)(-200 1200);
WIRE 16 -1 (50 2950)(-200 2950);
WIRE 16 -1 (50 3000)(-200 3000);
WIRE 16 -1 (50 3100)(-200 3100);
WIRE 16 -1 (50 2550)(-200 2550);
WIRE 16 -1 (50 2500)(-200 2500);
WIRE 16 -1 (50 1950)(-200 1950);
WIRE 16 -1 (50 2050)(-200 2050);
WIRE 16 -1 (50 4050)(-200 4050);
WIRE 16 -1 (50 4100)(-200 4100);
WIRE 16 -1 (50 3900)(-200 3900);
WIRE 16 -1 (50 3850)(-200 3850);
WIRE 16 -1 (50 3800)(-200 3800);
WIRE 16 -1 (50 3750)(-200 3750);
WIRE 16 -1 (50 3700)(-200 3700);
WIRE 16 -1 (50 3650)(-200 3650);
WIRE 16 -1 (50 3600)(-200 3600);
WIRE 16 -1 (50 3550)(-200 3550);
WIRE 16 -1 (50 1300)(-200 1300);
WIRE 16 -1 (50 1350)(-200 1350);
WIRE 16 -1 (50 1400)(-200 1400);
WIRE 16 -1 (50 1450)(-200 1450);
WIRE 16 -1 (50 3050)(-200 3050);
WIRE 16 -1 (50 2400)(-200 2400);
WIRE 16 -1 (50 2350)(-200 2350);
WIRE 16 -1 (50 1900)(-200 1900);
WIRE 16 -1 (50 2100)(-200 2100);
WIRE 16 -1 (50 1750)(-200 1750);
WIRE 16 -1 (50 2200)(-200 2200);
WIRE 16 -1 (50 2150)(-200 2150);
WIRE 16 -1 (50 1650)(-200 1650);
WIRE 16 -1 (50 1500)(-200 1500);
WIRE 16 -1 (2300 3250)(2100 3250);
WIRE 16 -1 (2300 3150)(2100 3150);
WIRE 16 -1 (2300 3550)(2100 3550);
WIRE 16 -1 (2300 3450)(2100 3450);
WIRE 16 -1 (2300 3350)(2100 3350);
WIRE 16 -1 (2500 3500)(2100 3500);
WIRE 16 -1 (2500 3400)(2100 3400);
WIRE 16 -1 (2500 3300)(2100 3300);
WIRE 16 -1 (2500 3200)(2100 3200);
WIRE 16 -1 (2500 3100)(2100 3100);
WIRE 16 -1 (2300 3750)(2100 3750);
WIRE 16 -1 (2300 3650)(2100 3650);
WIRE 16 -1 (2300 4050)(2100 4050);
WIRE 16 -1 (2300 3950)(2100 3950);
WIRE 16 -1 (2300 3850)(2100 3850);
WIRE 16 -1 (2500 4000)(2100 4000);
WIRE 16 -1 (2500 3900)(2100 3900);
WIRE 16 -1 (2500 3800)(2100 3800);
WIRE 16 -1 (2500 3700)(2100 3700);
WIRE 16 -1 (2500 3600)(2100 3600);
WIRE 16 -1 (2300 4350)(2100 4350);
WIRE 16 -1 (2300 4250)(2100 4250);
WIRE 16 -1 (2300 4150)(2100 4150);
WIRE 16 -1 (2300 4550)(2100 4550);
WIRE 16 -1 (2300 4450)(2100 4450);
WIRE 16 -1 (2500 4600)(2100 4600);
WIRE 16 -1 (2500 4500)(2100 4500);
WIRE 16 -1 (2500 4400)(2100 4400);
WIRE 16 -1 (2500 4300)(2100 4300);
WIRE 16 -1 (2500 4200)(2100 4200);
WIRE 16 -1 (2500 4100)(2100 4100);
WIRE 16 -1 (2300 4850)(2100 4850);
WIRE 16 -1 (2300 4750)(2100 4750);
WIRE 16 -1 (2300 4650)(2100 4650);
WIRE 16 -1 (2500 4800)(2100 4800);
WIRE 16 -1 (2500 4700)(2100 4700);
DOT 1 (2750 2350);
DOT 1 (950 1400);
DOT 1 (2750 1300);
DOT 1 (4150 3450);
DOT 1 (4150 3500);
DOT 1 (4150 3400);
DOT 1 (4150 3350);
DOT 1 (4150 3300);
DOT 1 (4150 3250);
DOT 1 (4150 3200);
DOT 1 (4150 3100);
DOT 1 (4150 3150);
DOT 1 (4150 3050);
DOT 1 (4150 3000);
DOT 1 (4150 2950);
DOT 1 (4150 2900);
DOT 1 (4150 2800);
DOT 1 (4150 2850);
DOT 1 (4150 2750);
DOT 1 (4150 2700);
DOT 1 (4150 2650);
DOT 1 (4150 2550);
DOT 1 (4150 2600);
DOT 1 (4150 2500);
DOT 1 (4150 2450);
DOT 1 (4150 2400);
DOT 1 (4150 2350);
DOT 1 (4150 2300);
DOT 1 (4150 2250);
DOT 1 (4150 2200);
DOT 1 (4150 2150);
DOT 1 (4150 2100);
DOT 1 (4150 2050);
DOT 1 (4150 2000);
DOT 1 (4150 1950);
DOT 1 (4150 1900);
DOT 1 (4150 1850);
DOT 1 (4150 1800);
DOT 1 (4150 1750);
DOT 1 (4150 1650);
DOT 1 (4150 1700);
DOT 1 (4150 1600);
DOT 1 (4150 1500);
DOT 1 (4150 1550);
DOT 1 (4150 1400);
DOT 1 (4150 1450);
DOT 1 (4150 1350);
DOT 1 (4150 1300);
DOT 1 (4150 1250);
DOT 1 (2750 3500);
DOT 1 (2750 3450);
DOT 1 (2750 3400);
DOT 1 (2750 3350);
DOT 1 (2750 3300);
DOT 1 (2750 3200);
DOT 1 (2750 3250);
DOT 1 (2750 3050);
DOT 1 (2750 3000);
DOT 1 (2750 2950);
DOT 1 (2750 2900);
DOT 1 (2750 2800);
DOT 1 (2750 2850);
DOT 1 (2750 2750);
DOT 1 (2750 2700);
DOT 1 (2750 2650);
DOT 1 (2750 2600);
DOT 1 (2750 2550);
DOT 1 (2750 2500);
DOT 1 (2750 2450);
DOT 1 (2750 2400);
DOT 1 (2750 2300);
DOT 1 (2750 2250);
DOT 1 (2750 2200);
DOT 1 (2750 2150);
DOT 1 (2750 2100);
DOT 1 (2750 2050);
DOT 1 (2300 2500);
DOT 1 (2750 2000);
DOT 1 (2750 1950);
DOT 1 (2750 1900);
DOT 1 (2750 1850);
DOT 1 (2750 1800);
DOT 1 (2750 1750);
DOT 1 (2750 1700);
DOT 1 (2750 1650);
DOT 1 (2750 1600);
DOT 1 (2750 1500);
DOT 1 (2750 1550);
DOT 1 (2750 1450);
DOT 1 (2750 1400);
DOT 1 (2750 1350);
DOT 1 (2750 1250);
DOT 1 (950 2500);
DOT 1 (950 2450);
DOT 1 (950 2400);
DOT 1 (950 2350);
DOT 1 (950 2200);
DOT 1 (950 2050);
DOT 1 (950 1900);
DOT 1 (950 1950);
DOT 1 (950 1850);
DOT 1 (950 1800);
DOT 1 (950 1750);
DOT 1 (950 1700);
DOT 1 (950 1650);
DOT 1 (950 1600);
DOT 1 (950 1500);
DOT 1 (950 1550);
DOT 1 (950 1450);
DOT 1 (950 1350);
DOT 1 (950 1300);
DOT 1 (950 1250);
DOT 1 (950 1200);
DOT 1 (950 1150);
DOT 1 (950 1100);
DOT 1 (950 1050);
DOT 1 (950 950);
DOT 1 (950 900);
DOT 1 (950 850);
DOT 1 (-2650 1200);
DOT 1 (-1500 1550);
DOT 1 (-1400 1500);
DOT 1 (950 2000);
DOT 1 (2750 3150);
DOT 1 (2750 3100);
DOT 1 (950 1000);
FORCENOTE
SMBUS ADDR: 0XA2
(-3700 450) 0;
DISPLAY LEFT (-3700 450);
DISPLAY 1.361702 (-3700 450);
PAINT PURPLE (-3700 450);
FORCENOTE
PLACE CAP NEAR DIMM CONNECTOR
(-2604 750) 0;
DISPLAY LEFT (-2604 750);
DISPLAY 1.021277 (-2604 750);
PAINT PURPLE (-2604 750);
QUIT
